FILE_TYPE = MACRO_DRAWING;
SET COLOR_WIRE YELLOW;
SET COLOR_PROP MONO;
SET COLOR_DOT WHITE;
SET COLOR_ARC YELLOW;
SET COLOR_BODY GREEN;
SET COLOR_NOTE MONO;
SET PROP_DISPLAY VALUE;
SET PAGE_NUMBER P141;
FORCEADD CAP..2
(-3150 4375);
FORCEPROP 1 LAST PACK_TYPE 0402LF
J 0
(-2450 4375);
DISPLAY 0.617021 (-2450 4375);
PAINT SKYBLUE (-2450 4375);
FORCEPROP 1 LAST MATERIAL EMPTY
J 0
(-3075 4375);
DISPLAY 0.617021 (-3075 4375);
PAINT RED (-3075 4375);
FORCEPROP 1 LAST VOLTAGE 50V
J 0
(-2600 4375);
DISPLAY 0.617021 (-2600 4375);
PAINT SKYBLUE (-2600 4375);
FORCEPROP 1 LAST LOCATION C9G12
J 1
(-3775 4375);
DISPLAY 0.617021 (-3775 4375);
PAINT AQUA (-3775 4375);
FORCEPROP 1 LAST VALUE 4700PF
J 2
(-3250 4375);
DISPLAY 0.617021 (-3250 4375);
PAINT SKYBLUE (-3250 4375);
FORCEPROP 1 LAST PART_NUMBER A36096-066
J 1
(-3550 4375);
DISPLAY 0.617021 (-3550 4375);
PAINT BLUE (-3550 4375);
FORCEPROP 1 LAST TOLERANCE 10%
J 2
(-2650 4375);
DISPLAY 0.617021 (-2650 4375);
PAINT SKYBLUE (-2650 4375);
FORCEPROP 0 LAST GROUP NI_I210&RJ45
J 0
(-3325 4225);
DISPLAY 0.638298 (-3325 4225);
PAINT BROWN (-3325 4225);
DISPLAY BOTH (-3325 4225);
FORCEPROP 2 LAST BOM_COST NT_GBE_BASE
J 0
(-2900 4475);
DISPLAY 1.021277 (-2900 4475);
PAINT ORANGE (-2900 4475);
DISPLAY INVISIBLE (-2900 4475);
FORCEPROP 2 LAST ROOM NIC_SPRV
J 0
(-2900 4425);
DISPLAY 1.021277 (-2900 4425);
PAINT ORANGE (-2900 4425);
DISPLAY INVISIBLE (-2900 4425);
FORCEPROP 1 LASTPIN (-3050 4375) $PN 2
J 0
(-3065 4390);
DISPLAY 0.787234 (-3065 4390);
PAINT ORANGE (-3065 4390);
DISPLAY INVISIBLE (-3065 4390);
FORCEPROP 2 LAST NO_XNET_CONNECTION 1
J 0
(-3150 4625);
PAINT MONO (-3150 4625);
DISPLAY INVISIBLE (-3150 4625);
FORCEPROP 2 LAST $SEC 1
J 0
(-3150 4625);
PAINT MONO (-3150 4625);
DISPLAY INVISIBLE (-3150 4625);
FORCEPROP 2 LAST CDS_SEC 1
J 0
(-3150 4625);
PAINT MONO (-3150 4625);
DISPLAY INVISIBLE (-3150 4625);
FORCEPROP 1 LAST PATH I100
J 0
(-3150 4575);
DISPLAY 0.978723 (-3150 4575);
PAINT WHITE (-3150 4575);
DISPLAY INVISIBLE (-3150 4575);
FORCEPROP 2 LAST CDS_LIB mstr_discrete
J 0
(-3150 4375);
PAINT MONO (-3150 4375);
DISPLAY INVISIBLE (-3150 4375);
FORCEPROP 1 LASTPIN (-3250 4375) $PN 1
J 0
(-3260 4390);
DISPLAY 0.787234 (-3260 4390);
PAINT ORANGE (-3260 4390);
DISPLAY INVISIBLE (-3260 4390);
FORCEPROP 2 LAST CDS_LOCATION C9G12
J 1
(-3600 4375);
DISPLAY 0.617021 (-3600 4375);
PAINT AQUA (-3600 4375);
DISPLAY INVISIBLE (-3600 4375);
FORCEADD CAP..2
(-2825 4075);
FORCEPROP 0 LAST GROUP NI_I210&RJ45
J 0
(-2750 3950);
DISPLAY 0.638298 (-2750 3950);
PAINT BROWN (-2750 3950);
DISPLAY BOTH (-2750 3950);
FORCEPROP 1 LAST PACK_TYPE 0402LF
J 0
(-2350 4075);
DISPLAY 0.617021 (-2350 4075);
PAINT SKYBLUE (-2350 4075);
FORCEPROP 1 LAST VALUE 4700PF
J 2
(-2900 4150);
DISPLAY 0.617021 (-2900 4150);
PAINT SKYBLUE (-2900 4150);
FORCEPROP 1 LAST PART_NUMBER A36096-066
J 0
(-3325 4075);
DISPLAY 0.617021 (-3325 4075);
PAINT BLUE (-3325 4075);
FORCEPROP 1 LAST VOLTAGE 50V
J 0
(-2500 4075);
DISPLAY 0.617021 (-2500 4075);
PAINT SKYBLUE (-2500 4075);
FORCEPROP 1 LASTPIN (-2925 4075) $PN 1
J 0
(-2935 4090);
DISPLAY 0.787234 (-2935 4090);
PAINT ORANGE (-2935 4090);
FORCEPROP 1 LAST LOCATION C9G16
J 1
(-3550 4075);
DISPLAY 0.617021 (-3550 4075);
PAINT AQUA (-3550 4075);
FORCEPROP 1 LASTPIN (-2725 4075) $PN 2
J 0
(-2740 4090);
DISPLAY 0.787234 (-2740 4090);
PAINT ORANGE (-2740 4090);
FORCEPROP 1 LAST TOLERANCE 10%
J 2
(-2575 4075);
DISPLAY 0.617021 (-2575 4075);
PAINT SKYBLUE (-2575 4075);
FORCEPROP 1 LAST MATERIAL EMPTY
J 0
(-2725 4150);
DISPLAY 0.617021 (-2725 4150);
PAINT RED (-2725 4150);
FORCEPROP 2 LAST ROOM NIC_SPRV
J 0
(-2575 4125);
DISPLAY 1.021277 (-2575 4125);
PAINT ORANGE (-2575 4125);
DISPLAY INVISIBLE (-2575 4125);
FORCEPROP 2 LAST BOM_COST NT_GBE_BASE
J 0
(-2575 4175);
DISPLAY 1.021277 (-2575 4175);
PAINT ORANGE (-2575 4175);
DISPLAY INVISIBLE (-2575 4175);
FORCEPROP 2 LAST NO_XNET_CONNECTION 1
J 0
(-2825 4325);
PAINT MONO (-2825 4325);
DISPLAY INVISIBLE (-2825 4325);
FORCEPROP 1 LAST PATH I101
J 0
(-2825 4275);
DISPLAY 0.978723 (-2825 4275);
PAINT WHITE (-2825 4275);
DISPLAY INVISIBLE (-2825 4275);
FORCEPROP 2 LAST CDS_LOCATION C9G16
J 1
(-3275 4075);
DISPLAY 0.617021 (-3275 4075);
PAINT AQUA (-3275 4075);
DISPLAY INVISIBLE (-3275 4075);
FORCEPROP 2 LAST CDS_LIB mstr_discrete
J 0
(-2825 4075);
PAINT MONO (-2825 4075);
DISPLAY INVISIBLE (-2825 4075);
FORCEPROP 2 LAST SEC 1
J 0
(-2825 4325);
PAINT MONO (-2825 4325);
DISPLAY INVISIBLE (-2825 4325);
FORCEPROP 2 LAST SEC_TYPE 0402LF
J 0
(-2825 4325);
DISPLAY 1.021277 (-2825 4325);
PAINT ORANGE (-2825 4325);
DISPLAY INVISIBLE (-2825 4325);
FORCEADD CAP..2
(-3100 4025);
FORCEPROP 1 LAST VALUE 4700PF
J 2
(-3200 3925);
DISPLAY 0.617021 (-3200 3925);
PAINT SKYBLUE (-3200 3925);
FORCEPROP 0 LAST GROUP NI_I210&RJ45
J 0
(-3100 3875);
DISPLAY 0.638298 (-3100 3875);
PAINT BROWN (-3100 3875);
DISPLAY BOTH (-3100 3875);
FORCEPROP 1 LAST PACK_TYPE 0402LF
J 0
(-2350 4025);
DISPLAY 0.617021 (-2350 4025);
PAINT SKYBLUE (-2350 4025);
FORCEPROP 1 LAST MATERIAL EMPTY
J 0
(-3025 3925);
DISPLAY 0.617021 (-3025 3925);
PAINT RED (-3025 3925);
FORCEPROP 1 LAST VOLTAGE 50V
J 0
(-2500 4025);
DISPLAY 0.617021 (-2500 4025);
PAINT SKYBLUE (-2500 4025);
FORCEPROP 1 LAST PART_NUMBER A36096-066
J 1
(-3400 4025);
DISPLAY 0.617021 (-3400 4025);
PAINT BLUE (-3400 4025);
FORCEPROP 1 LASTPIN (-3000 4025) $PN 2
J 0
(-3015 4040);
DISPLAY 0.787234 (-3015 4040);
PAINT ORANGE (-3015 4040);
FORCEPROP 1 LAST TOLERANCE 10%
J 2
(-2575 4025);
DISPLAY 0.617021 (-2575 4025);
PAINT SKYBLUE (-2575 4025);
FORCEPROP 1 LASTPIN (-3200 4025) $PN 1
J 0
(-3210 4040);
DISPLAY 0.787234 (-3210 4040);
PAINT ORANGE (-3210 4040);
FORCEPROP 1 LAST LOCATION C9G13
J 1
(-3625 4025);
DISPLAY 0.617021 (-3625 4025);
PAINT AQUA (-3625 4025);
FORCEPROP 2 LAST BOM_COST NT_GBE_BASE
J 0
(-2850 4125);
DISPLAY 1.021277 (-2850 4125);
PAINT ORANGE (-2850 4125);
DISPLAY INVISIBLE (-2850 4125);
FORCEPROP 1 LAST PATH I102
J 0
(-3100 4225);
DISPLAY 0.978723 (-3100 4225);
PAINT WHITE (-3100 4225);
DISPLAY INVISIBLE (-3100 4225);
FORCEPROP 2 LAST NO_XNET_CONNECTION 1
J 0
(-3100 4275);
PAINT MONO (-3100 4275);
DISPLAY INVISIBLE (-3100 4275);
FORCEPROP 2 LAST ROOM NIC_SPRV
J 0
(-2850 4075);
DISPLAY 1.021277 (-2850 4075);
PAINT ORANGE (-2850 4075);
DISPLAY INVISIBLE (-2850 4075);
FORCEPROP 2 LAST CDS_LIB mstr_discrete
J 0
(-3100 4025);
PAINT MONO (-3100 4025);
DISPLAY INVISIBLE (-3100 4025);
FORCEPROP 2 LAST CDS_LOCATION C9G13
J 1
(-3550 4025);
DISPLAY 0.617021 (-3550 4025);
PAINT AQUA (-3550 4025);
DISPLAY INVISIBLE (-3550 4025);
FORCEPROP 2 LAST SEC 1
J 0
(-3100 4275);
PAINT MONO (-3100 4275);
DISPLAY INVISIBLE (-3100 4275);
FORCEPROP 2 LAST SEC_TYPE 0402LF
J 0
(-3100 4275);
DISPLAY 1.021277 (-3100 4275);
PAINT ORANGE (-3100 4275);
DISPLAY INVISIBLE (-3100 4275);
FORCEADD OFFPAGE..4
(-1425 4425);
FORCEPROP 2 LAST $XR0 181 
J 0
(-1239 4425);
DISPLAY 0.638298 (-1239 4425);
PAINT MONO (-1239 4425);
FORCEPROP 2 LAST CDS_LIB mstr_standard
J 0
(-1425 4425);
PAINT MONO (-1425 4425);
DISPLAY INVISIBLE (-1425 4425);
FORCEPROP 2 LAST PATH I103
J 0
(-1375 4500);
DISPLAY 1.021277 (-1375 4500);
PAINT ORANGE (-1375 4500);
DISPLAY INVISIBLE (-1375 4500);
FORCEPROP 1 LAST OFFPAGE TRUE
J 0
(-1100 4300);
DISPLAY 0.872340 (-1100 4300);
PAINT GREEN (-1100 4300);
DISPLAY INVISIBLE (-1100 4300);
FORCEPROP 1 LAST COMMENT_BODY TRUE
J 0
(-1450 4325);
DISPLAY 0.872340 (-1450 4325);
PAINT GREEN (-1450 4325);
DISPLAY INVISIBLE (-1450 4325);
FORCEADD OFFPAGE..2
(-1425 4075);
FORCEPROP 2 LAST $XR0 181 
J 0
(-1236 4075);
DISPLAY 0.638298 (-1236 4075);
PAINT MONO (-1236 4075);
FORCEPROP 2 LAST PATH I104
J 0
(-1375 4150);
DISPLAY 1.021277 (-1375 4150);
PAINT ORANGE (-1375 4150);
DISPLAY INVISIBLE (-1375 4150);
FORCEPROP 2 LAST CDS_LIB mstr_standard
J 0
(-1425 4075);
PAINT MONO (-1425 4075);
DISPLAY INVISIBLE (-1425 4075);
FORCEPROP 1 LAST OFFPAGE TRUE
J 0
(-1100 3950);
DISPLAY 0.872340 (-1100 3950);
PAINT GREEN (-1100 3950);
DISPLAY INVISIBLE (-1100 3950);
FORCEPROP 1 LAST COMMENT_BODY TRUE
J 0
(-1470 3980);
DISPLAY 0.872340 (-1470 3980);
PAINT GREEN (-1470 3980);
DISPLAY INVISIBLE (-1470 3980);
FORCEADD OFFPAGE..4
(-1425 4375);
FORCEPROP 2 LAST $XR0 181 
J 0
(-1239 4375);
DISPLAY 0.638298 (-1239 4375);
PAINT MONO (-1239 4375);
FORCEPROP 2 LAST CDS_LIB mstr_standard
J 0
(-1425 4375);
PAINT MONO (-1425 4375);
DISPLAY INVISIBLE (-1425 4375);
FORCEPROP 2 LAST PATH I105
J 0
(-1250 4450);
DISPLAY 1.021277 (-1250 4450);
PAINT ORANGE (-1250 4450);
DISPLAY INVISIBLE (-1250 4450);
FORCEPROP 1 LAST OFFPAGE TRUE
J 0
(-1100 4250);
DISPLAY 0.872340 (-1100 4250);
PAINT GREEN (-1100 4250);
DISPLAY INVISIBLE (-1100 4250);
FORCEPROP 1 LAST COMMENT_BODY TRUE
J 0
(-1450 4275);
DISPLAY 0.872340 (-1450 4275);
PAINT GREEN (-1450 4275);
DISPLAY INVISIBLE (-1450 4275);
FORCEADD OFFPAGE..2
(-1425 4025);
FORCEPROP 2 LAST $XR0 181 
J 0
(-1236 4025);
DISPLAY 0.638298 (-1236 4025);
PAINT MONO (-1236 4025);
FORCEPROP 2 LAST PATH I106
J 0
(-1250 4100);
DISPLAY 1.021277 (-1250 4100);
PAINT ORANGE (-1250 4100);
DISPLAY INVISIBLE (-1250 4100);
FORCEPROP 2 LAST CDS_LIB mstr_standard
J 0
(-1425 4025);
PAINT MONO (-1425 4025);
DISPLAY INVISIBLE (-1425 4025);
FORCEPROP 1 LAST OFFPAGE TRUE
J 0
(-1100 3900);
DISPLAY 0.872340 (-1100 3900);
PAINT GREEN (-1100 3900);
DISPLAY INVISIBLE (-1100 3900);
FORCEPROP 1 LAST COMMENT_BODY TRUE
J 0
(-1470 3930);
DISPLAY 0.872340 (-1470 3930);
PAINT GREEN (-1470 3930);
DISPLAY INVISIBLE (-1470 3930);
FORCEADD SKT-RJ45-LED-XFOR-1-GP..1
(-1650 1825);
FORCEPROP 2 LASTPIN (-2050 2200) $PN L2
J 2
(-2060 2210);
DISPLAY 0.808511 (-2060 2210);
PAINT ORANGE (-2060 2210);
FORCEPROP 2 LASTPIN (-2050 1250) $PN L4
J 2
(-2060 1260);
DISPLAY 0.808511 (-2060 1260);
PAINT ORANGE (-2060 1260);
FORCEPROP 2 LASTPIN (-2050 1450) $PN L3
J 2
(-2060 1460);
DISPLAY 0.808511 (-2060 1460);
PAINT ORANGE (-2060 1460);
FORCEPROP 1 LAST LOCATION JA9G1
J 0
(-1900 2475);
DISPLAY 0.617021 (-1900 2475);
PAINT GREEN (-1900 2475);
FORCEPROP 2 LASTPIN (-2050 1700) $PN R8
J 2
(-2060 1710);
DISPLAY 0.808511 (-2060 1710);
PAINT ORANGE (-2060 1710);
FORCEPROP 2 LASTPIN (-2050 2400) $PN L1
J 2
(-2060 2410);
DISPLAY 0.808511 (-2060 2410);
PAINT ORANGE (-2060 2410);
FORCEPROP 2 LASTPIN (-2050 1950) $PN R3
J 2
(-2060 1960);
DISPLAY 0.808511 (-2060 1960);
PAINT ORANGE (-2060 1960);
FORCEPROP 2 LASTPIN (-2050 1900) $PN R4
J 2
(-2060 1910);
DISPLAY 0.808511 (-2060 1910);
PAINT ORANGE (-2060 1910);
FORCEPROP 2 LASTPIN (-2050 1750) $PN R7
J 2
(-2060 1760);
DISPLAY 0.808511 (-2060 1760);
PAINT ORANGE (-2060 1760);
FORCEPROP 2 LASTPIN (-2050 2000) $PN R2
J 2
(-2060 2010);
DISPLAY 0.808511 (-2060 2010);
PAINT ORANGE (-2060 2010);
FORCEPROP 2 LASTPIN (-2050 1800) $PN R6
J 2
(-2060 1810);
DISPLAY 0.808511 (-2060 1810);
PAINT ORANGE (-2060 1810);
FORCEPROP 2 LASTPIN (-2050 1850) $PN R5
J 2
(-2060 1860);
DISPLAY 0.808511 (-2060 1860);
PAINT ORANGE (-2060 1860);
FORCEPROP 2 LASTPIN (-1250 2400) $PN 1
J 0
(-1240 2410);
DISPLAY 0.808511 (-1240 2410);
PAINT ORANGE (-1240 2410);
FORCEPROP 2 LASTPIN (-1250 1250) $PN 2
J 0
(-1240 1260);
DISPLAY 0.808511 (-1240 1260);
PAINT ORANGE (-1240 1260);
FORCEPROP 1 LAST VALUE SKT-RJ45-LED-XFOR-1-GP
J 0
(-1900 1150);
DISPLAY 0.617021 (-1900 1150);
PAINT GREEN (-1900 1150);
FORCEPROP 2 LASTPIN (-2050 1550) $PN R11
J 2
(-2060 1560);
DISPLAY 0.808511 (-2060 1560);
PAINT ORANGE (-2060 1560);
FORCEPROP 2 LASTPIN (-2050 1600) $PN R10
J 2
(-2060 1610);
DISPLAY 0.808511 (-2060 1610);
PAINT ORANGE (-2060 1610);
FORCEPROP 2 LASTPIN (-2050 1650) $PN R9
J 2
(-2060 1660);
DISPLAY 0.808511 (-2060 1660);
PAINT ORANGE (-2060 1660);
FORCEPROP 2 LASTPIN (-2050 2100) $PN R1
J 2
(-2060 2110);
DISPLAY 0.808511 (-2060 2110);
PAINT ORANGE (-2060 2110);
FORCEPROP 0 LAST GROUP NI_I210&RJ45
J 0
(-1900 1100);
DISPLAY 0.638298 (-1900 1100);
PAINT BROWN (-1900 1100);
DISPLAY BOTH (-1900 1100);
FORCEPROP 1 LAST PATH I129
J 0
(-1650 1825);
DISPLAY 0.617021 (-1650 1825);
PAINT GREEN (-1650 1825);
DISPLAY INVISIBLE (-1650 1825);
FORCEPROP 1 LAST CDS_LMAN_SYM_OUTLINE -250,625,250,-625
J 0
(-1650 1825);
DISPLAY 0.468085 (-1650 1825);
PAINT GREEN (-1650 1825);
DISPLAY INVISIBLE (-1650 1825);
FORCEPROP 2 LAST CDS_LIB w_hdl
J 0
(-1650 1825);
PAINT MONO (-1650 1825);
DISPLAY INVISIBLE (-1650 1825);
FORCEPROP 1 LAST PART_NUMBER 022.10001.0S51
J 0
(-1650 1825);
DISPLAY 0.617021 (-1650 1825);
PAINT GREEN (-1650 1825);
DISPLAY INVISIBLE (-1650 1825);
FORCEPROP 2 LAST SEC_TYPE SOCKET-G2
J 0
(-1900 2525);
DISPLAY 1.021277 (-1900 2525);
PAINT ORANGE (-1900 2525);
DISPLAY INVISIBLE (-1900 2525);
FORCEPROP 2 LAST SEC 1
J 0
(-1900 2525);
DISPLAY 0.680851 (-1900 2525);
PAINT MONO (-1900 2525);
DISPLAY INVISIBLE (-1900 2525);
FORCEPROP 1 LAST PACK_TYPE SOCKET-G2
J 0
(-1650 1825);
DISPLAY 0.617021 (-1650 1825);
PAINT GREEN (-1650 1825);
DISPLAY INVISIBLE (-1650 1825);
FORCEADD RES..1
R 4
(-2800 2725);
FORCEPROP 1 LASTPIN (-2900 2725) $PN 2
J 0
(-2887 2738);
DISPLAY 0.617021 (-2887 2738);
PAINT ORANGE (-2887 2738);
FORCEPROP 1 LAST MATERIAL CHIP
J 0
(-2675 2675);
DISPLAY 0.617021 (-2675 2675);
PAINT SKYBLUE (-2675 2675);
FORCEPROP 1 LAST PACK_TYPE 0402
J 0
(-2550 2675);
DISPLAY 0.617021 (-2550 2675);
PAINT SKYBLUE (-2550 2675);
FORCEPROP 1 LAST WATTAGE 1/16W
J 2
(-2700 2675);
DISPLAY 0.617021 (-2700 2675);
PAINT SKYBLUE (-2700 2675);
FORCEPROP 1 LAST LOCATION R9G2
J 0
(-3025 2775);
DISPLAY 0.617021 (-3025 2775);
PAINT AQUA (-3025 2775);
FORCEPROP 1 LAST VALUE 75
J 2
(-2975 2675);
DISPLAY 0.617021 (-2975 2675);
PAINT SKYBLUE (-2975 2675);
FORCEPROP 1 LASTPIN (-2700 2725) $PN 1
J 0
(-2737 2738);
DISPLAY 0.617021 (-2737 2738);
PAINT ORANGE (-2737 2738);
FORCEPROP 0 LAST GROUP NI_I210&RJ45
J 0
(-3025 2625);
DISPLAY 0.638298 (-3025 2625);
PAINT BROWN (-3025 2625);
DISPLAY BOTH (-3025 2625);
FORCEPROP 1 LAST TOLERANCE 1.0%
J 0
(-2925 2675);
DISPLAY 0.617021 (-2925 2675);
PAINT SKYBLUE (-2925 2675);
FORCEPROP 1 LAST PART_NUMBER G21796-267
J 0
(-2875 2775);
DISPLAY 0.617021 (-2875 2775);
PAINT BLUE (-2875 2775);
FORCEPROP 2 LAST BOM_COST PROC
R 2
J 2
(-2800 2725);
PAINT MONO (-2800 2725);
DISPLAY INVISIBLE (-2800 2725);
FORCEPROP 2 LAST CDS_LIB mstr_discrete
R 2
J 0
(-2800 2725);
PAINT ORANGE (-2800 2725);
DISPLAY INVISIBLE (-2800 2725);
FORCEPROP 2 LAST CDS_SEC 1
R 2
J 0
(-2750 2525);
DISPLAY 1.021277 (-2750 2525);
PAINT ORANGE (-2750 2525);
DISPLAY INVISIBLE (-2750 2525);
FORCEPROP 2 LAST $SEC 1
R 2
J 0
(-2750 2525);
DISPLAY 0.680851 (-2750 2525);
PAINT MONO (-2750 2525);
DISPLAY INVISIBLE (-2750 2525);
FORCEPROP 2 LAST ROOM PROC_SIDEBAND
R 2
J 0
(-2725 2800);
DISPLAY 0.617021 (-2725 2800);
PAINT ORANGE (-2725 2800);
DISPLAY INVISIBLE (-2725 2800);
FORCEPROP 1 LAST PATH I134
R 2
J 0
(-2750 2575);
DISPLAY 0.978723 (-2750 2575);
PAINT WHITE (-2750 2575);
DISPLAY INVISIBLE (-2750 2575);
FORCEPROP 2 LAST CDS_LOCATION R9G2
R 2
J 0
(-2750 2675);
DISPLAY 0.617021 (-2750 2675);
PAINT AQUA (-2750 2675);
DISPLAY INVISIBLE (-2750 2675);
FORCEADD RES..1
R 4
(-2800 2525);
FORCEPROP 1 LAST PART_NUMBER G21796-267
J 0
(-2875 2575);
DISPLAY 0.617021 (-2875 2575);
PAINT BLUE (-2875 2575);
FORCEPROP 1 LAST MATERIAL CHIP
J 0
(-2675 2475);
DISPLAY 0.617021 (-2675 2475);
PAINT SKYBLUE (-2675 2475);
FORCEPROP 1 LAST WATTAGE 1/16W
J 2
(-2700 2475);
DISPLAY 0.617021 (-2700 2475);
PAINT SKYBLUE (-2700 2475);
FORCEPROP 1 LAST TOLERANCE 1.0%
J 0
(-2925 2475);
DISPLAY 0.617021 (-2925 2475);
PAINT SKYBLUE (-2925 2475);
FORCEPROP 1 LASTPIN (-2700 2525) $PN 1
J 0
(-2737 2538);
DISPLAY 0.617021 (-2737 2538);
PAINT ORANGE (-2737 2538);
FORCEPROP 1 LAST LOCATION R9G3
J 0
(-3025 2575);
DISPLAY 0.617021 (-3025 2575);
PAINT AQUA (-3025 2575);
FORCEPROP 1 LAST VALUE 75
J 2
(-2975 2475);
DISPLAY 0.617021 (-2975 2475);
PAINT SKYBLUE (-2975 2475);
FORCEPROP 1 LASTPIN (-2900 2525) $PN 2
J 0
(-2887 2538);
DISPLAY 0.617021 (-2887 2538);
PAINT ORANGE (-2887 2538);
FORCEPROP 0 LAST GROUP NI_I210&RJ45
J 0
(-3025 2425);
DISPLAY 0.638298 (-3025 2425);
PAINT BROWN (-3025 2425);
DISPLAY BOTH (-3025 2425);
FORCEPROP 1 LAST PACK_TYPE 0402
J 0
(-2550 2475);
DISPLAY 0.617021 (-2550 2475);
PAINT SKYBLUE (-2550 2475);
FORCEPROP 1 LAST PATH I135
R 2
J 0
(-2750 2375);
DISPLAY 0.978723 (-2750 2375);
PAINT WHITE (-2750 2375);
DISPLAY INVISIBLE (-2750 2375);
FORCEPROP 2 LAST ROOM PROC_SIDEBAND
R 2
J 0
(-2725 2600);
DISPLAY 0.617021 (-2725 2600);
PAINT ORANGE (-2725 2600);
DISPLAY INVISIBLE (-2725 2600);
FORCEPROP 2 LAST $SEC 1
R 2
J 0
(-2750 2325);
DISPLAY 0.680851 (-2750 2325);
PAINT MONO (-2750 2325);
DISPLAY INVISIBLE (-2750 2325);
FORCEPROP 2 LAST CDS_SEC 1
R 2
J 0
(-2750 2325);
DISPLAY 1.021277 (-2750 2325);
PAINT ORANGE (-2750 2325);
DISPLAY INVISIBLE (-2750 2325);
FORCEPROP 2 LAST CDS_LIB mstr_discrete
R 2
J 0
(-2800 2525);
PAINT ORANGE (-2800 2525);
DISPLAY INVISIBLE (-2800 2525);
FORCEPROP 2 LAST BOM_COST PROC
R 2
J 2
(-2800 2525);
PAINT MONO (-2800 2525);
DISPLAY INVISIBLE (-2800 2525);
FORCEPROP 2 LAST CDS_LOCATION R9G3
R 2
J 0
(-2750 2475);
DISPLAY 0.617021 (-2750 2475);
PAINT AQUA (-2750 2475);
DISPLAY INVISIBLE (-2750 2475);
FORCEADD OFFPAGE..1
(-3750 2725);
FORCEPROP 2 LAST $XR0 139 
J 0
(-4002 2725);
DISPLAY 0.638298 (-4002 2725);
PAINT MONO (-4002 2725);
FORCEPROP 2 LAST PATH I136
J 0
(-3700 2800);
DISPLAY 1.021277 (-3700 2800);
PAINT ORANGE (-3700 2800);
DISPLAY INVISIBLE (-3700 2800);
FORCEPROP 2 LAST CDS_LIB mstr_standard
J 0
(-3750 2725);
PAINT MONO (-3750 2725);
DISPLAY INVISIBLE (-3750 2725);
FORCEPROP 1 LAST OFFPAGE TRUE
J 0
(-3425 2600);
DISPLAY 0.872340 (-3425 2600);
PAINT GREEN (-3425 2600);
DISPLAY INVISIBLE (-3425 2600);
FORCEPROP 1 LAST COMMENT_BODY TRUE
J 0
(-3625 2625);
DISPLAY 0.872340 (-3625 2625);
PAINT GREEN (-3625 2625);
DISPLAY INVISIBLE (-3625 2625);
FORCEADD OFFPAGE..1
(-3750 2525);
FORCEPROP 2 LAST $XR0 139 
J 0
(-4002 2525);
DISPLAY 0.638298 (-4002 2525);
PAINT MONO (-4002 2525);
FORCEPROP 2 LAST PATH I137
J 0
(-3700 2600);
DISPLAY 1.021277 (-3700 2600);
PAINT ORANGE (-3700 2600);
DISPLAY INVISIBLE (-3700 2600);
FORCEPROP 2 LAST CDS_LIB mstr_standard
J 0
(-3750 2525);
PAINT MONO (-3750 2525);
DISPLAY INVISIBLE (-3750 2525);
FORCEPROP 1 LAST OFFPAGE TRUE
J 0
(-3425 2400);
DISPLAY 0.872340 (-3425 2400);
PAINT GREEN (-3425 2400);
DISPLAY INVISIBLE (-3425 2400);
FORCEPROP 1 LAST COMMENT_BODY TRUE
J 0
(-3625 2425);
DISPLAY 0.872340 (-3625 2425);
PAINT GREEN (-3625 2425);
DISPLAY INVISIBLE (-3625 2425);
FORCEADD CAP..1
(-3350 2375);
FORCEPROP 1 LAST TOLERANCE 10%
J 0
(-3300 2325);
DISPLAY 0.617021 (-3300 2325);
PAINT SKYBLUE (-3300 2325);
FORCEPROP 1 LAST PACK_TYPE 0402LF
J 0
(-3300 2175);
DISPLAY 0.617021 (-3300 2175);
PAINT SKYBLUE (-3300 2175);
FORCEPROP 1 LASTPIN (-3350 2275) $PN 2
J 0
(-3340 2255);
DISPLAY 0.617021 (-3340 2255);
PAINT ORANGE (-3340 2255);
FORCEPROP 1 LASTPIN (-3350 2475) $PN 1
J 0
(-3340 2455);
DISPLAY 0.617021 (-3340 2455);
PAINT ORANGE (-3340 2455);
FORCEPROP 1 LAST MATERIAL X7R
J 0
(-3300 2275);
DISPLAY 0.617021 (-3300 2275);
PAINT SKYBLUE (-3300 2275);
FORCEPROP 1 LAST PART_NUMBER A36096-049
J 0
(-3300 2225);
DISPLAY 0.617021 (-3300 2225);
PAINT BLUE (-3300 2225);
FORCEPROP 1 LAST VOLTAGE 50V
J 0
(-3300 2375);
DISPLAY 0.617021 (-3300 2375);
PAINT SKYBLUE (-3300 2375);
FORCEPROP 1 LAST VALUE 470PF
J 0
(-3300 2425);
DISPLAY 0.617021 (-3300 2425);
PAINT SKYBLUE (-3300 2425);
FORCEPROP 1 LAST LOCATION C9G3
J 0
(-3300 2475);
DISPLAY 0.617021 (-3300 2475);
PAINT AQUA (-3300 2475);
FORCEPROP 0 LAST GROUP NI_I210&RJ45
J 0
(-3250 2150);
DISPLAY 0.638298 (-3250 2150);
PAINT BROWN (-3250 2150);
DISPLAY BOTH (-3250 2150);
FORCEPROP 1 LAST PATH I138
J 0
(-3300 2525);
DISPLAY 0.978723 (-3300 2525);
PAINT WHITE (-3300 2525);
DISPLAY INVISIBLE (-3300 2525);
FORCEPROP 0 LAST CDS_SEC 1
J 0
(-3300 2525);
PAINT MONO (-3300 2525);
DISPLAY INVISIBLE (-3300 2525);
FORCEPROP 2 LAST SEC_TYPE 0402LF
J 0
(-3300 2575);
DISPLAY 1.021277 (-3300 2575);
PAINT ORANGE (-3300 2575);
DISPLAY INVISIBLE (-3300 2575);
FORCEPROP 2 LAST CDS_LOCATION C9G3
J 0
(-3300 2475);
DISPLAY 0.617021 (-3300 2475);
PAINT AQUA (-3300 2475);
DISPLAY INVISIBLE (-3300 2475);
FORCEPROP 2 LAST SEC 1
J 0
(-3300 2575);
PAINT MONO (-3300 2575);
DISPLAY INVISIBLE (-3300 2575);
FORCEPROP 2 LAST BOM_COST NT_GBE_BASE
J 0
(-3300 2575);
DISPLAY 1.021277 (-3300 2575);
PAINT ORANGE (-3300 2575);
DISPLAY INVISIBLE (-3300 2575);
FORCEPROP 2 LAST CDS_LIB mstr_discrete
J 0
(-3350 2375);
PAINT ORANGE (-3350 2375);
DISPLAY INVISIBLE (-3350 2375);
FORCEPROP 2 LAST ROOM NIC_SPRV
J 0
(-3300 2525);
DISPLAY 1.021277 (-3300 2525);
PAINT ORANGE (-3300 2525);
DISPLAY INVISIBLE (-3300 2525);
FORCEADD GND..1
(-3350 2175);
FORCEPROP 3 LASTPIN (-3350 2225) SIG_NAME GND\g
J 0
(-3340 2235);
DISPLAY 0.659574 (-3340 2235);
PAINT MONO (-3340 2235);
DISPLAY INVISIBLE (-3340 2235);
FORCEPROP 1 LAST PATH I139
J 0
(-3275 2175);
DISPLAY 0.872340 (-3275 2175);
PAINT AQUA (-3275 2175);
DISPLAY INVISIBLE (-3275 2175);
FORCEPROP 1 LAST SIZE 1B
J 0
(-3275 2125);
DISPLAY 0.872340 (-3275 2125);
PAINT AQUA (-3275 2125);
DISPLAY INVISIBLE (-3275 2125);
FORCEPROP 2 LAST CDS_LIB mstr_symbols
J 0
(-3350 2175);
PAINT ORANGE (-3350 2175);
DISPLAY INVISIBLE (-3350 2175);
FORCEPROP 1 LAST VOLTAGE 0.0V
J 0
(-3395 2132);
DISPLAY 0.340426 (-3395 2132);
PAINT SKYBLUE (-3395 2132);
DISPLAY INVISIBLE (-3395 2132);
FORCEPROP 1 LAST BODY_TYPE PLUMBING
J 0
(-3395 2132);
DISPLAY 0.340426 (-3395 2132);
PAINT GREEN (-3395 2132);
DISPLAY INVISIBLE (-3395 2132);
FORCEPROP 1 LAST HDL_POWER GND
J 0
(-3350 2325);
DISPLAY 0.872340 (-3350 2325);
PAINT GREEN (-3350 2325);
DISPLAY INVISIBLE (-3350 2325);
FORCEADD CAP..1
(-3650 2375);
FORCEPROP 1 LAST PART_NUMBER A36096-049
J 0
(-3600 2225);
DISPLAY 0.617021 (-3600 2225);
PAINT BLUE (-3600 2225);
FORCEPROP 1 LAST VALUE 470PF
J 0
(-3600 2425);
DISPLAY 0.617021 (-3600 2425);
PAINT SKYBLUE (-3600 2425);
FORCEPROP 1 LASTPIN (-3650 2275) $PN 2
J 0
(-3640 2255);
DISPLAY 0.617021 (-3640 2255);
PAINT ORANGE (-3640 2255);
FORCEPROP 1 LASTPIN (-3650 2475) $PN 1
J 0
(-3640 2455);
DISPLAY 0.617021 (-3640 2455);
PAINT ORANGE (-3640 2455);
FORCEPROP 1 LAST LOCATION C9G1
J 0
(-3600 2475);
DISPLAY 0.617021 (-3600 2475);
PAINT AQUA (-3600 2475);
FORCEPROP 1 LAST MATERIAL X7R
J 0
(-3600 2275);
DISPLAY 0.617021 (-3600 2275);
PAINT SKYBLUE (-3600 2275);
FORCEPROP 1 LAST VOLTAGE 50V
J 0
(-3600 2375);
DISPLAY 0.617021 (-3600 2375);
PAINT SKYBLUE (-3600 2375);
FORCEPROP 1 LAST PACK_TYPE 0402LF
J 0
(-3600 2175);
DISPLAY 0.617021 (-3600 2175);
PAINT SKYBLUE (-3600 2175);
FORCEPROP 1 LAST TOLERANCE 10%
J 0
(-3600 2325);
DISPLAY 0.617021 (-3600 2325);
PAINT SKYBLUE (-3600 2325);
FORCEPROP 0 LAST GROUP NI_I210&RJ45
J 0
(-3650 2125);
DISPLAY 0.638298 (-3650 2125);
PAINT BROWN (-3650 2125);
DISPLAY BOTH (-3650 2125);
FORCEPROP 1 LAST PATH I140
J 0
(-3600 2525);
DISPLAY 0.978723 (-3600 2525);
PAINT WHITE (-3600 2525);
DISPLAY INVISIBLE (-3600 2525);
FORCEPROP 0 LAST CDS_SEC 1
J 0
(-3600 2525);
PAINT MONO (-3600 2525);
DISPLAY INVISIBLE (-3600 2525);
FORCEPROP 2 LAST CDS_LIB mstr_discrete
J 0
(-3650 2375);
PAINT ORANGE (-3650 2375);
DISPLAY INVISIBLE (-3650 2375);
FORCEPROP 2 LAST ROOM NIC_SPRV
J 0
(-3600 2525);
DISPLAY 1.021277 (-3600 2525);
PAINT ORANGE (-3600 2525);
DISPLAY INVISIBLE (-3600 2525);
FORCEPROP 2 LAST CDS_LOCATION C9G1
J 0
(-3600 2475);
DISPLAY 0.617021 (-3600 2475);
PAINT AQUA (-3600 2475);
DISPLAY INVISIBLE (-3600 2475);
FORCEPROP 2 LAST SEC 1
J 0
(-3600 2575);
PAINT MONO (-3600 2575);
DISPLAY INVISIBLE (-3600 2575);
FORCEPROP 2 LAST BOM_COST NT_GBE_BASE
J 0
(-3600 2575);
DISPLAY 1.021277 (-3600 2575);
PAINT ORANGE (-3600 2575);
DISPLAY INVISIBLE (-3600 2575);
FORCEPROP 2 LAST SEC_TYPE 0402LF
J 0
(-3600 2575);
DISPLAY 1.021277 (-3600 2575);
PAINT ORANGE (-3600 2575);
DISPLAY INVISIBLE (-3600 2575);
FORCEADD GND..1
(-3650 2175);
FORCEPROP 3 LASTPIN (-3650 2225) SIG_NAME GND\g
J 0
(-3640 2235);
DISPLAY 0.659574 (-3640 2235);
PAINT MONO (-3640 2235);
DISPLAY INVISIBLE (-3640 2235);
FORCEPROP 1 LAST SIZE 1B
J 0
(-3575 2125);
DISPLAY 0.872340 (-3575 2125);
PAINT AQUA (-3575 2125);
DISPLAY INVISIBLE (-3575 2125);
FORCEPROP 1 LAST VOLTAGE 0.0V
J 0
(-3695 2132);
DISPLAY 0.340426 (-3695 2132);
PAINT SKYBLUE (-3695 2132);
DISPLAY INVISIBLE (-3695 2132);
FORCEPROP 2 LAST CDS_LIB mstr_symbols
J 0
(-3650 2175);
PAINT ORANGE (-3650 2175);
DISPLAY INVISIBLE (-3650 2175);
FORCEPROP 1 LAST PATH I141
J 0
(-3575 2175);
DISPLAY 0.872340 (-3575 2175);
PAINT AQUA (-3575 2175);
DISPLAY INVISIBLE (-3575 2175);
FORCEPROP 1 LAST BODY_TYPE PLUMBING
J 0
(-3695 2132);
DISPLAY 0.340426 (-3695 2132);
PAINT GREEN (-3695 2132);
DISPLAY INVISIBLE (-3695 2132);
FORCEPROP 1 LAST HDL_POWER GND
J 0
(-3650 2325);
DISPLAY 0.872340 (-3650 2325);
PAINT GREEN (-3650 2325);
DISPLAY INVISIBLE (-3650 2325);
FORCEADD OFFPAGE..6
(-3050 2000);
FORCEPROP 2 LAST $XR0 141 
J 0
(-3330 2000);
DISPLAY 0.638298 (-3330 2000);
PAINT MONO (-3330 2000);
FORCEPROP 2 LAST CDS_LIB mstr_standard
J 0
(-3050 2000);
PAINT ORANGE (-3050 2000);
DISPLAY INVISIBLE (-3050 2000);
FORCEPROP 2 LAST PATH I142
J 0
(-3325 2050);
DISPLAY 1.021277 (-3325 2050);
PAINT ORANGE (-3325 2050);
DISPLAY INVISIBLE (-3325 2050);
FORCEPROP 1 LAST OFFPAGE TRUE
J 0
(-2725 1875);
DISPLAY 0.872340 (-2725 1875);
PAINT GREEN (-2725 1875);
DISPLAY INVISIBLE (-2725 1875);
FORCEPROP 1 LAST COMMENT_BODY TRUE
J 0
(-2950 1925);
DISPLAY 0.872340 (-2950 1925);
PAINT GREEN (-2950 1925);
DISPLAY INVISIBLE (-2950 1925);
FORCEADD OFFPAGE..6
(-3050 1950);
FORCEPROP 2 LAST $XR0 141 
J 0
(-3330 1950);
DISPLAY 0.638298 (-3330 1950);
PAINT MONO (-3330 1950);
FORCEPROP 2 LAST CDS_LIB mstr_standard
J 0
(-3050 1950);
PAINT ORANGE (-3050 1950);
DISPLAY INVISIBLE (-3050 1950);
FORCEPROP 2 LAST PATH I143
J 0
(-3325 2000);
DISPLAY 1.021277 (-3325 2000);
PAINT ORANGE (-3325 2000);
DISPLAY INVISIBLE (-3325 2000);
FORCEPROP 1 LAST OFFPAGE TRUE
J 0
(-2725 1825);
DISPLAY 0.872340 (-2725 1825);
PAINT GREEN (-2725 1825);
DISPLAY INVISIBLE (-2725 1825);
FORCEPROP 1 LAST COMMENT_BODY TRUE
J 0
(-2950 1875);
DISPLAY 0.872340 (-2950 1875);
PAINT GREEN (-2950 1875);
DISPLAY INVISIBLE (-2950 1875);
FORCEADD OFFPAGE..6
(-3050 1900);
FORCEPROP 2 LAST $XR0 141 
J 0
(-3330 1900);
DISPLAY 0.638298 (-3330 1900);
PAINT MONO (-3330 1900);
FORCEPROP 2 LAST CDS_LIB mstr_standard
J 0
(-3050 1900);
PAINT ORANGE (-3050 1900);
DISPLAY INVISIBLE (-3050 1900);
FORCEPROP 2 LAST PATH I144
J 0
(-3325 1950);
DISPLAY 1.021277 (-3325 1950);
PAINT ORANGE (-3325 1950);
DISPLAY INVISIBLE (-3325 1950);
FORCEPROP 1 LAST OFFPAGE TRUE
J 0
(-2725 1775);
DISPLAY 0.872340 (-2725 1775);
PAINT GREEN (-2725 1775);
DISPLAY INVISIBLE (-2725 1775);
FORCEPROP 1 LAST COMMENT_BODY TRUE
J 0
(-2950 1825);
DISPLAY 0.872340 (-2950 1825);
PAINT GREEN (-2950 1825);
DISPLAY INVISIBLE (-2950 1825);
FORCEADD OFFPAGE..6
(-3050 1850);
FORCEPROP 2 LAST $XR0 141 
J 0
(-3330 1850);
DISPLAY 0.638298 (-3330 1850);
PAINT MONO (-3330 1850);
FORCEPROP 2 LAST CDS_LIB mstr_standard
J 0
(-3050 1850);
PAINT ORANGE (-3050 1850);
DISPLAY INVISIBLE (-3050 1850);
FORCEPROP 2 LAST PATH I145
J 0
(-3325 1900);
DISPLAY 1.021277 (-3325 1900);
PAINT ORANGE (-3325 1900);
DISPLAY INVISIBLE (-3325 1900);
FORCEPROP 1 LAST OFFPAGE TRUE
J 0
(-2725 1725);
DISPLAY 0.872340 (-2725 1725);
PAINT GREEN (-2725 1725);
DISPLAY INVISIBLE (-2725 1725);
FORCEPROP 1 LAST COMMENT_BODY TRUE
J 0
(-2950 1775);
DISPLAY 0.872340 (-2950 1775);
PAINT GREEN (-2950 1775);
DISPLAY INVISIBLE (-2950 1775);
FORCEADD GND..1
(-3450 1700);
FORCEPROP 3 LASTPIN (-3450 1750) SIG_NAME GND\g
J 0
(-3440 1760);
DISPLAY 0.659574 (-3440 1760);
PAINT MONO (-3440 1760);
DISPLAY INVISIBLE (-3440 1760);
FORCEPROP 1 LAST SIZE 1B
J 0
(-3375 1650);
DISPLAY 0.872340 (-3375 1650);
PAINT AQUA (-3375 1650);
DISPLAY INVISIBLE (-3375 1650);
FORCEPROP 1 LAST VOLTAGE 0.0V
J 0
(-3495 1657);
DISPLAY 0.340426 (-3495 1657);
PAINT SKYBLUE (-3495 1657);
DISPLAY INVISIBLE (-3495 1657);
FORCEPROP 1 LAST PATH I146
J 0
(-3375 1700);
DISPLAY 0.872340 (-3375 1700);
PAINT AQUA (-3375 1700);
DISPLAY INVISIBLE (-3375 1700);
FORCEPROP 2 LAST CDS_LIB mstr_symbols
J 0
(-3450 1700);
PAINT MONO (-3450 1700);
DISPLAY INVISIBLE (-3450 1700);
FORCEPROP 1 LAST BODY_TYPE PLUMBING
J 0
(-3495 1657);
DISPLAY 0.340426 (-3495 1657);
PAINT GREEN (-3495 1657);
DISPLAY INVISIBLE (-3495 1657);
FORCEPROP 1 LAST HDL_POWER GND
J 0
(-3450 1850);
DISPLAY 0.872340 (-3450 1850);
PAINT GREEN (-3450 1850);
DISPLAY INVISIBLE (-3450 1850);
FORCEADD OFFPAGE..6
(-3050 1750);
FORCEPROP 2 LAST $XR0 141 
J 0
(-3330 1750);
DISPLAY 0.638298 (-3330 1750);
PAINT MONO (-3330 1750);
FORCEPROP 2 LAST CDS_LIB mstr_standard
J 0
(-3050 1750);
PAINT ORANGE (-3050 1750);
DISPLAY INVISIBLE (-3050 1750);
FORCEPROP 2 LAST PATH I147
J 0
(-3325 1800);
DISPLAY 1.021277 (-3325 1800);
PAINT ORANGE (-3325 1800);
DISPLAY INVISIBLE (-3325 1800);
FORCEPROP 1 LAST OFFPAGE TRUE
J 0
(-2725 1625);
DISPLAY 0.872340 (-2725 1625);
PAINT GREEN (-2725 1625);
DISPLAY INVISIBLE (-2725 1625);
FORCEPROP 1 LAST COMMENT_BODY TRUE
J 0
(-2950 1675);
DISPLAY 0.872340 (-2950 1675);
PAINT GREEN (-2950 1675);
DISPLAY INVISIBLE (-2950 1675);
FORCEADD OFFPAGE..6
(-3050 1700);
FORCEPROP 2 LAST $XR0 141 
J 0
(-3330 1700);
DISPLAY 0.638298 (-3330 1700);
PAINT MONO (-3330 1700);
FORCEPROP 2 LAST CDS_LIB mstr_standard
J 0
(-3050 1700);
PAINT ORANGE (-3050 1700);
DISPLAY INVISIBLE (-3050 1700);
FORCEPROP 2 LAST PATH I148
J 0
(-3325 1750);
DISPLAY 1.021277 (-3325 1750);
PAINT ORANGE (-3325 1750);
DISPLAY INVISIBLE (-3325 1750);
FORCEPROP 1 LAST OFFPAGE TRUE
J 0
(-2725 1575);
DISPLAY 0.872340 (-2725 1575);
PAINT GREEN (-2725 1575);
DISPLAY INVISIBLE (-2725 1575);
FORCEPROP 1 LAST COMMENT_BODY TRUE
J 0
(-2950 1625);
DISPLAY 0.872340 (-2950 1625);
PAINT GREEN (-2950 1625);
DISPLAY INVISIBLE (-2950 1625);
FORCEADD OFFPAGE..6
(-3050 1650);
FORCEPROP 2 LAST $XR0 141 
J 0
(-3330 1650);
DISPLAY 0.638298 (-3330 1650);
PAINT MONO (-3330 1650);
FORCEPROP 2 LAST CDS_LIB mstr_standard
J 0
(-3050 1650);
PAINT ORANGE (-3050 1650);
DISPLAY INVISIBLE (-3050 1650);
FORCEPROP 2 LAST PATH I149
J 0
(-3325 1700);
DISPLAY 1.021277 (-3325 1700);
PAINT ORANGE (-3325 1700);
DISPLAY INVISIBLE (-3325 1700);
FORCEPROP 1 LAST OFFPAGE TRUE
J 0
(-2725 1525);
DISPLAY 0.872340 (-2725 1525);
PAINT GREEN (-2725 1525);
DISPLAY INVISIBLE (-2725 1525);
FORCEPROP 1 LAST COMMENT_BODY TRUE
J 0
(-2950 1575);
DISPLAY 0.872340 (-2950 1575);
PAINT GREEN (-2950 1575);
DISPLAY INVISIBLE (-2950 1575);
FORCEADD OFFPAGE..6
(-3050 1600);
FORCEPROP 2 LAST $XR0 141 
J 0
(-3330 1600);
DISPLAY 0.638298 (-3330 1600);
PAINT MONO (-3330 1600);
FORCEPROP 2 LAST CDS_LIB mstr_standard
J 0
(-3050 1600);
PAINT ORANGE (-3050 1600);
DISPLAY INVISIBLE (-3050 1600);
FORCEPROP 2 LAST PATH I150
J 0
(-3325 1650);
DISPLAY 1.021277 (-3325 1650);
PAINT ORANGE (-3325 1650);
DISPLAY INVISIBLE (-3325 1650);
FORCEPROP 1 LAST OFFPAGE TRUE
J 0
(-2725 1475);
DISPLAY 0.872340 (-2725 1475);
PAINT GREEN (-2725 1475);
DISPLAY INVISIBLE (-2725 1475);
FORCEPROP 1 LAST COMMENT_BODY TRUE
J 0
(-2950 1525);
DISPLAY 0.872340 (-2950 1525);
PAINT GREEN (-2950 1525);
DISPLAY INVISIBLE (-2950 1525);
FORCEADD OFFPAGE..1
(-3050 1550);
FORCEPROP 2 LAST $XR0 141 
J 0
(-3332 1550);
DISPLAY 0.638298 (-3332 1550);
PAINT MONO (-3332 1550);
FORCEPROP 2 LAST CDS_LIB mstr_standard
J 0
(-3050 1550);
PAINT ORANGE (-3050 1550);
DISPLAY INVISIBLE (-3050 1550);
FORCEPROP 2 LAST PATH I151
J 0
(-3325 1600);
DISPLAY 1.021277 (-3325 1600);
PAINT ORANGE (-3325 1600);
DISPLAY INVISIBLE (-3325 1600);
FORCEPROP 1 LAST OFFPAGE TRUE
J 0
(-2725 1425);
DISPLAY 0.872340 (-2725 1425);
PAINT GREEN (-2725 1425);
DISPLAY INVISIBLE (-2725 1425);
FORCEPROP 1 LAST COMMENT_BODY TRUE
J 0
(-2925 1450);
DISPLAY 0.872340 (-2925 1450);
PAINT GREEN (-2925 1450);
DISPLAY INVISIBLE (-2925 1450);
FORCEADD CAP..1
(-3200 1050);
FORCEPROP 0 LAST GROUP NI_I210&RJ45
J 0
(-3150 800);
DISPLAY 0.638298 (-3150 800);
PAINT BROWN (-3150 800);
DISPLAY BOTH (-3150 800);
FORCEPROP 1 LAST LOCATION C9G2
J 0
(-3150 1150);
DISPLAY 0.617021 (-3150 1150);
PAINT AQUA (-3150 1150);
FORCEPROP 1 LAST VALUE 470PF
J 0
(-3150 1100);
DISPLAY 0.617021 (-3150 1100);
PAINT SKYBLUE (-3150 1100);
FORCEPROP 1 LAST PACK_TYPE 0402LF
J 0
(-3150 850);
DISPLAY 0.617021 (-3150 850);
PAINT SKYBLUE (-3150 850);
FORCEPROP 1 LAST PART_NUMBER A36096-049
J 0
(-3150 900);
DISPLAY 0.617021 (-3150 900);
PAINT BLUE (-3150 900);
FORCEPROP 1 LAST TOLERANCE 10%
J 0
(-3150 1000);
DISPLAY 0.617021 (-3150 1000);
PAINT SKYBLUE (-3150 1000);
FORCEPROP 1 LAST VOLTAGE 50V
J 0
(-3150 1050);
DISPLAY 0.617021 (-3150 1050);
PAINT SKYBLUE (-3150 1050);
FORCEPROP 1 LAST MATERIAL X7R
J 0
(-3150 950);
DISPLAY 0.617021 (-3150 950);
PAINT SKYBLUE (-3150 950);
FORCEPROP 1 LASTPIN (-3200 950) $PN 2
J 0
(-3190 930);
DISPLAY 0.617021 (-3190 930);
PAINT ORANGE (-3190 930);
FORCEPROP 1 LASTPIN (-3200 1150) $PN 1
J 0
(-3190 1130);
DISPLAY 0.617021 (-3190 1130);
PAINT ORANGE (-3190 1130);
FORCEPROP 1 LAST PATH I152
J 0
(-3150 1200);
DISPLAY 0.978723 (-3150 1200);
PAINT WHITE (-3150 1200);
DISPLAY INVISIBLE (-3150 1200);
FORCEPROP 0 LAST CDS_SEC 1
J 0
(-3150 1150);
PAINT MONO (-3150 1150);
DISPLAY INVISIBLE (-3150 1150);
FORCEPROP 2 LAST CDS_LIB mstr_discrete
J 0
(-3200 1050);
PAINT ORANGE (-3200 1050);
DISPLAY INVISIBLE (-3200 1050);
FORCEPROP 2 LAST CDS_LOCATION C9G2
J 0
(-3025 1025);
DISPLAY 0.617021 (-3025 1025);
PAINT AQUA (-3025 1025);
DISPLAY INVISIBLE (-3025 1025);
FORCEPROP 2 LAST SEC 1
J 0
(-3150 1250);
PAINT MONO (-3150 1250);
DISPLAY INVISIBLE (-3150 1250);
FORCEPROP 2 LAST BOM_COST NT_GBE_BASE
J 0
(-3150 1200);
DISPLAY 1.021277 (-3150 1200);
PAINT ORANGE (-3150 1200);
DISPLAY INVISIBLE (-3150 1200);
FORCEPROP 2 LAST SEC_TYPE 0402LF
J 0
(-3150 1250);
DISPLAY 1.021277 (-3150 1250);
PAINT ORANGE (-3150 1250);
DISPLAY INVISIBLE (-3150 1250);
FORCEPROP 2 LAST ROOM NIC_SPRV
J 0
(-3150 1150);
DISPLAY 1.021277 (-3150 1150);
PAINT ORANGE (-3150 1150);
DISPLAY INVISIBLE (-3150 1150);
FORCEADD P3V3_STBY..1
(-3200 1300);
FORCEPROP 3 LASTPIN (-3200 1250) SIG_NAME P3V3_STBY\g
J 0
(-3190 1260);
DISPLAY 0.659574 (-3190 1260);
PAINT MONO (-3190 1260);
DISPLAY INVISIBLE (-3190 1260);
FORCEPROP 1 LAST PATH I153
J 0
(-3155 1302);
DISPLAY 0.340426 (-3155 1302);
PAINT GREEN (-3155 1302);
DISPLAY INVISIBLE (-3155 1302);
FORCEPROP 2 LAST CDS_LIB mstr_symbols
J 0
(-3200 1300);
PAINT ORANGE (-3200 1300);
DISPLAY INVISIBLE (-3200 1300);
FORCEPROP 1 LAST SIZE 1B
J 0
(-3155 1322);
DISPLAY 0.340426 (-3155 1322);
PAINT GREEN (-3155 1322);
DISPLAY INVISIBLE (-3155 1322);
FORCEPROP 1 LAST VOLTAGE 3.3V
J 0
(-3245 1257);
DISPLAY 0.340426 (-3245 1257);
PAINT SKYBLUE (-3245 1257);
DISPLAY INVISIBLE (-3245 1257);
FORCEPROP 1 LAST BODY_TYPE PLUMBING
J 0
(-3245 1257);
DISPLAY 0.340426 (-3245 1257);
PAINT GREEN (-3245 1257);
DISPLAY INVISIBLE (-3245 1257);
FORCEPROP 1 LAST HDL_POWER P3V3_STBY
J 0
(-3500 1175);
DISPLAY 0.872340 (-3500 1175);
PAINT ORANGE (-3500 1175);
DISPLAY INVISIBLE (-3500 1175);
FORCEADD GND..1
(-3200 850);
FORCEPROP 3 LASTPIN (-3200 900) SIG_NAME GND\g
J 0
(-3190 910);
DISPLAY 0.659574 (-3190 910);
PAINT MONO (-3190 910);
DISPLAY INVISIBLE (-3190 910);
FORCEPROP 2 LAST CDS_LIB mstr_symbols
J 0
(-3200 850);
PAINT ORANGE (-3200 850);
DISPLAY INVISIBLE (-3200 850);
FORCEPROP 1 LAST SIZE 1B
J 0
(-3125 800);
DISPLAY 0.872340 (-3125 800);
PAINT AQUA (-3125 800);
DISPLAY INVISIBLE (-3125 800);
FORCEPROP 1 LAST VOLTAGE 0.0V
J 0
(-3245 807);
DISPLAY 0.340426 (-3245 807);
PAINT SKYBLUE (-3245 807);
DISPLAY INVISIBLE (-3245 807);
FORCEPROP 1 LAST PATH I155
J 0
(-3125 850);
DISPLAY 0.872340 (-3125 850);
PAINT AQUA (-3125 850);
DISPLAY INVISIBLE (-3125 850);
FORCEPROP 1 LAST BODY_TYPE PLUMBING
J 0
(-3245 807);
DISPLAY 0.340426 (-3245 807);
PAINT GREEN (-3245 807);
DISPLAY INVISIBLE (-3245 807);
FORCEPROP 1 LAST HDL_POWER GND
J 0
(-3200 1000);
DISPLAY 0.872340 (-3200 1000);
PAINT GREEN (-3200 1000);
DISPLAY INVISIBLE (-3200 1000);
FORCEADD RES..1
R 4
(-2875 1200);
FORCEPROP 1 LAST WATTAGE 1/16W
J 2
(-2700 1125);
DISPLAY 0.617021 (-2700 1125);
PAINT SKYBLUE (-2700 1125);
FORCEPROP 1 LAST PACK_TYPE 0402
J 0
(-2825 1075);
DISPLAY 0.617021 (-2825 1075);
PAINT SKYBLUE (-2825 1075);
FORCEPROP 1 LAST LOCATION R9G4
J 0
(-2975 1300);
DISPLAY 0.617021 (-2975 1300);
PAINT AQUA (-2975 1300);
FORCEPROP 1 LASTPIN (-2775 1200) $PN 1
J 0
(-2812 1213);
DISPLAY 0.617021 (-2812 1213);
PAINT ORANGE (-2812 1213);
FORCEPROP 1 LAST MATERIAL CHIP
J 0
(-2950 1075);
DISPLAY 0.617021 (-2950 1075);
PAINT SKYBLUE (-2950 1075);
FORCEPROP 1 LAST TOLERANCE 5%
J 0
(-2900 1125);
DISPLAY 0.617021 (-2900 1125);
PAINT SKYBLUE (-2900 1125);
FORCEPROP 1 LAST VALUE 0.0
J 2
(-2925 1125);
DISPLAY 0.617021 (-2925 1125);
PAINT SKYBLUE (-2925 1125);
FORCEPROP 1 LASTPIN (-2975 1200) $PN 2
J 0
(-2962 1213);
DISPLAY 0.617021 (-2962 1213);
PAINT ORANGE (-2962 1213);
FORCEPROP 1 LAST PART_NUMBER G21497-005
J 0
(-2975 1250);
DISPLAY 0.617021 (-2975 1250);
PAINT BLUE (-2975 1250);
FORCEPROP 0 LAST GROUP NI_I210&RJ45
J 0
(-2950 1025);
DISPLAY 0.638298 (-2950 1025);
PAINT BROWN (-2950 1025);
DISPLAY BOTH (-2950 1025);
FORCEPROP 2 LAST BOM_COST NT_GBE_BASE
R 2
J 0
(-2825 1000);
DISPLAY 1.021277 (-2825 1000);
PAINT ORANGE (-2825 1000);
DISPLAY INVISIBLE (-2825 1000);
FORCEPROP 2 LAST SEC_TYPE 0402
R 2
J 0
(-2825 1000);
DISPLAY 1.021277 (-2825 1000);
PAINT ORANGE (-2825 1000);
DISPLAY INVISIBLE (-2825 1000);
FORCEPROP 2 LAST ROOM NIC_SPRV
R 2
J 0
(-2825 1050);
DISPLAY 1.021277 (-2825 1050);
PAINT ORANGE (-2825 1050);
DISPLAY INVISIBLE (-2825 1050);
FORCEPROP 2 LAST SEC 1
R 2
J 0
(-2825 1000);
PAINT MONO (-2825 1000);
DISPLAY INVISIBLE (-2825 1000);
FORCEPROP 2 LAST CDS_LOCATION R9G4
R 2
J 0
(-2825 1150);
DISPLAY 0.617021 (-2825 1150);
PAINT AQUA (-2825 1150);
DISPLAY INVISIBLE (-2825 1150);
FORCEPROP 2 LAST CDS_LIB mstr_discrete
R 2
J 0
(-2875 1200);
PAINT ORANGE (-2875 1200);
DISPLAY INVISIBLE (-2875 1200);
FORCEPROP 0 LAST CDS_SEC 1
R 2
J 0
(-2825 1050);
PAINT MONO (-2825 1050);
DISPLAY INVISIBLE (-2825 1050);
FORCEPROP 1 LAST PATH I156
R 2
J 0
(-2825 1050);
DISPLAY 0.978723 (-2825 1050);
PAINT WHITE (-2825 1050);
DISPLAY INVISIBLE (-2825 1050);
FORCEADD RES..1
(-2800 1450);
FORCEPROP 1 LAST TOLERANCE 1%
J 0
(-2875 1400);
DISPLAY 0.617021 (-2875 1400);
PAINT SKYBLUE (-2875 1400);
FORCEPROP 1 LAST WATTAGE 1/16W
J 2
(-2675 1400);
DISPLAY 0.617021 (-2675 1400);
PAINT SKYBLUE (-2675 1400);
FORCEPROP 1 LAST PART_NUMBER G21796-009
J 0
(-2850 1500);
DISPLAY 0.617021 (-2850 1500);
PAINT BLUE (-2850 1500);
FORCEPROP 1 LASTPIN (-2700 1450) $PN 2
J 0
(-2738 1462);
DISPLAY 0.617021 (-2738 1462);
PAINT ORANGE (-2738 1462);
FORCEPROP 1 LASTPIN (-2900 1450) $PN 1
J 0
(-2888 1462);
DISPLAY 0.617021 (-2888 1462);
PAINT ORANGE (-2888 1462);
FORCEPROP 1 LAST MATERIAL CHIP
J 0
(-2650 1400);
DISPLAY 0.617021 (-2650 1400);
PAINT SKYBLUE (-2650 1400);
FORCEPROP 1 LAST LOCATION R9G1
J 0
(-3000 1500);
DISPLAY 0.617021 (-3000 1500);
PAINT AQUA (-3000 1500);
FORCEPROP 1 LAST VALUE 150.0
J 2
(-2900 1400);
DISPLAY 0.617021 (-2900 1400);
PAINT SKYBLUE (-2900 1400);
FORCEPROP 1 LAST PACK_TYPE 0402
J 0
(-2525 1400);
DISPLAY 0.617021 (-2525 1400);
PAINT SKYBLUE (-2525 1400);
FORCEPROP 0 LAST GROUP NI_I210&RJ45
J 0
(-2900 1350);
DISPLAY 0.638298 (-2900 1350);
PAINT BROWN (-2900 1350);
DISPLAY BOTH (-2900 1350);
FORCEPROP 2 LAST SEC_TYPE 0402
J 0
(-2850 1650);
DISPLAY 1.021277 (-2850 1650);
PAINT ORANGE (-2850 1650);
DISPLAY INVISIBLE (-2850 1650);
FORCEPROP 2 LAST SEC 1
J 0
(-2850 1650);
DISPLAY 0.680851 (-2850 1650);
PAINT MONO (-2850 1650);
DISPLAY INVISIBLE (-2850 1650);
FORCEPROP 2 LAST BOM_COST NT_GBE_BASE
J 0
(-2850 1600);
DISPLAY 1.021277 (-2850 1600);
PAINT ORANGE (-2850 1600);
DISPLAY INVISIBLE (-2850 1600);
FORCEPROP 2 LAST CDS_LIB mstr_discrete
J 0
(-2800 1450);
PAINT ORANGE (-2800 1450);
DISPLAY INVISIBLE (-2800 1450);
FORCEPROP 2 LAST CDS_LOCATION R9G1
J 0
(-2850 1500);
DISPLAY 0.617021 (-2850 1500);
PAINT AQUA (-2850 1500);
DISPLAY INVISIBLE (-2850 1500);
FORCEPROP 2 LAST ROOM NIC_SPRV
J 0
(-2850 1550);
DISPLAY 1.021277 (-2850 1550);
PAINT ORANGE (-2850 1550);
DISPLAY INVISIBLE (-2850 1550);
FORCEPROP 0 LAST CDS_SEC 1
J 0
(-2850 1550);
PAINT MONO (-2850 1550);
DISPLAY INVISIBLE (-2850 1550);
FORCEPROP 1 LAST PATH I157
J 0
(-2850 1600);
DISPLAY 0.978723 (-2850 1600);
PAINT WHITE (-2850 1600);
DISPLAY INVISIBLE (-2850 1600);
FORCEADD OFFPAGE..1
(-3750 1450);
FORCEPROP 2 LAST $XR0 139 
J 0
(-4002 1450);
DISPLAY 0.638298 (-4002 1450);
PAINT MONO (-4002 1450);
FORCEPROP 2 LAST CDS_LIB mstr_standard
J 0
(-3750 1450);
PAINT ORANGE (-3750 1450);
DISPLAY INVISIBLE (-3750 1450);
FORCEPROP 2 LAST PATH I158
J 0
(-4000 1500);
DISPLAY 1.021277 (-4000 1500);
PAINT ORANGE (-4000 1500);
DISPLAY INVISIBLE (-4000 1500);
FORCEPROP 1 LAST OFFPAGE TRUE
J 0
(-3425 1325);
DISPLAY 0.872340 (-3425 1325);
PAINT GREEN (-3425 1325);
DISPLAY INVISIBLE (-3425 1325);
FORCEPROP 1 LAST COMMENT_BODY TRUE
J 0
(-3625 1350);
DISPLAY 0.872340 (-3625 1350);
PAINT GREEN (-3625 1350);
DISPLAY INVISIBLE (-3625 1350);
FORCEADD CAP..1
(-3650 1300);
FORCEPROP 1 LAST VOLTAGE 50V
J 0
(-3600 1300);
DISPLAY 0.617021 (-3600 1300);
PAINT SKYBLUE (-3600 1300);
FORCEPROP 1 LASTPIN (-3650 1400) $PN 1
J 0
(-3640 1380);
DISPLAY 0.617021 (-3640 1380);
PAINT ORANGE (-3640 1380);
FORCEPROP 1 LASTPIN (-3650 1200) $PN 2
J 0
(-3640 1180);
DISPLAY 0.617021 (-3640 1180);
PAINT ORANGE (-3640 1180);
FORCEPROP 1 LAST LOCATION C9F22
J 0
(-3600 1400);
DISPLAY 0.617021 (-3600 1400);
PAINT AQUA (-3600 1400);
FORCEPROP 1 LAST VALUE 470PF
J 0
(-3600 1350);
DISPLAY 0.617021 (-3600 1350);
PAINT SKYBLUE (-3600 1350);
FORCEPROP 1 LAST TOLERANCE 10%
J 0
(-3600 1250);
DISPLAY 0.617021 (-3600 1250);
PAINT SKYBLUE (-3600 1250);
FORCEPROP 1 LAST MATERIAL X7R
J 0
(-3600 1200);
DISPLAY 0.617021 (-3600 1200);
PAINT SKYBLUE (-3600 1200);
FORCEPROP 1 LAST PART_NUMBER A36096-049
J 0
(-3600 1150);
DISPLAY 0.617021 (-3600 1150);
PAINT BLUE (-3600 1150);
FORCEPROP 1 LAST PACK_TYPE 0402LF
J 0
(-3600 1100);
DISPLAY 0.617021 (-3600 1100);
PAINT SKYBLUE (-3600 1100);
FORCEPROP 0 LAST GROUP NI_I210&RJ45
J 0
(-3725 1050);
DISPLAY 0.638298 (-3725 1050);
PAINT BROWN (-3725 1050);
DISPLAY BOTH (-3725 1050);
FORCEPROP 2 LAST BOM_COST NT_GBE_BASE
J 0
(-3600 1500);
DISPLAY 1.021277 (-3600 1500);
PAINT ORANGE (-3600 1500);
DISPLAY INVISIBLE (-3600 1500);
FORCEPROP 2 LAST SEC_TYPE 0402LF
J 0
(-3600 1500);
DISPLAY 1.021277 (-3600 1500);
PAINT ORANGE (-3600 1500);
DISPLAY INVISIBLE (-3600 1500);
FORCEPROP 2 LAST SEC 1
J 0
(-3600 1500);
PAINT MONO (-3600 1500);
DISPLAY INVISIBLE (-3600 1500);
FORCEPROP 2 LAST CDS_LOCATION C9F22
J 0
(-3600 1400);
DISPLAY 0.617021 (-3600 1400);
PAINT AQUA (-3600 1400);
DISPLAY INVISIBLE (-3600 1400);
FORCEPROP 2 LAST ROOM NIC_SPRV
J 0
(-3600 1450);
DISPLAY 1.021277 (-3600 1450);
PAINT ORANGE (-3600 1450);
DISPLAY INVISIBLE (-3600 1450);
FORCEPROP 2 LAST CDS_LIB mstr_discrete
J 0
(-3650 1300);
PAINT ORANGE (-3650 1300);
DISPLAY INVISIBLE (-3650 1300);
FORCEPROP 0 LAST CDS_SEC 1
J 0
(-3600 1450);
PAINT MONO (-3600 1450);
DISPLAY INVISIBLE (-3600 1450);
FORCEPROP 1 LAST PATH I159
J 0
(-3600 1450);
DISPLAY 0.978723 (-3600 1450);
PAINT WHITE (-3600 1450);
DISPLAY INVISIBLE (-3600 1450);
FORCEADD GND..1
(-3650 1100);
FORCEPROP 3 LASTPIN (-3650 1150) SIG_NAME GND\g
J 0
(-3640 1160);
DISPLAY 0.659574 (-3640 1160);
PAINT MONO (-3640 1160);
DISPLAY INVISIBLE (-3640 1160);
FORCEPROP 1 LAST PATH I160
J 0
(-3575 1100);
DISPLAY 0.872340 (-3575 1100);
PAINT AQUA (-3575 1100);
DISPLAY INVISIBLE (-3575 1100);
FORCEPROP 1 LAST VOLTAGE 0.0V
J 0
(-3695 1057);
DISPLAY 0.340426 (-3695 1057);
PAINT SKYBLUE (-3695 1057);
DISPLAY INVISIBLE (-3695 1057);
FORCEPROP 1 LAST SIZE 1B
J 0
(-3575 1050);
DISPLAY 0.872340 (-3575 1050);
PAINT AQUA (-3575 1050);
DISPLAY INVISIBLE (-3575 1050);
FORCEPROP 2 LAST CDS_LIB mstr_symbols
J 0
(-3650 1100);
PAINT ORANGE (-3650 1100);
DISPLAY INVISIBLE (-3650 1100);
FORCEPROP 1 LAST BODY_TYPE PLUMBING
J 0
(-3695 1057);
DISPLAY 0.340426 (-3695 1057);
PAINT GREEN (-3695 1057);
DISPLAY INVISIBLE (-3695 1057);
FORCEPROP 1 LAST HDL_POWER GND
J 0
(-3650 1250);
DISPLAY 0.872340 (-3650 1250);
PAINT GREEN (-3650 1250);
DISPLAY INVISIBLE (-3650 1250);
FORCEADD GND..1
(-1250 2275);
FORCEPROP 3 LASTPIN (-1250 2325) SIG_NAME GND\g
J 0
(-1240 2335);
DISPLAY 0.659574 (-1240 2335);
PAINT MONO (-1240 2335);
DISPLAY INVISIBLE (-1240 2335);
FORCEPROP 2 LAST CDS_LIB mstr_symbols
J 0
(-1250 2275);
PAINT ORANGE (-1250 2275);
DISPLAY INVISIBLE (-1250 2275);
FORCEPROP 1 LAST VOLTAGE 0.0V
J 0
(-1295 2232);
DISPLAY 0.340426 (-1295 2232);
PAINT SKYBLUE (-1295 2232);
DISPLAY INVISIBLE (-1295 2232);
FORCEPROP 1 LAST SIZE 1B
J 0
(-1175 2225);
DISPLAY 0.872340 (-1175 2225);
PAINT AQUA (-1175 2225);
DISPLAY INVISIBLE (-1175 2225);
FORCEPROP 1 LAST PATH I161
J 0
(-1175 2275);
DISPLAY 0.872340 (-1175 2275);
PAINT AQUA (-1175 2275);
DISPLAY INVISIBLE (-1175 2275);
FORCEPROP 1 LAST BODY_TYPE PLUMBING
J 0
(-1295 2232);
DISPLAY 0.340426 (-1295 2232);
PAINT GREEN (-1295 2232);
DISPLAY INVISIBLE (-1295 2232);
FORCEPROP 1 LAST HDL_POWER GND
J 0
(-1250 2425);
DISPLAY 0.872340 (-1250 2425);
PAINT GREEN (-1250 2425);
DISPLAY INVISIBLE (-1250 2425);
FORCEADD GND..1
(-1250 1125);
FORCEPROP 3 LASTPIN (-1250 1175) SIG_NAME GND\g
J 0
(-1240 1185);
DISPLAY 0.659574 (-1240 1185);
PAINT MONO (-1240 1185);
DISPLAY INVISIBLE (-1240 1185);
FORCEPROP 1 LAST PATH I162
J 0
(-1175 1125);
DISPLAY 0.872340 (-1175 1125);
PAINT AQUA (-1175 1125);
DISPLAY INVISIBLE (-1175 1125);
FORCEPROP 1 LAST SIZE 1B
J 0
(-1175 1075);
DISPLAY 0.872340 (-1175 1075);
PAINT AQUA (-1175 1075);
DISPLAY INVISIBLE (-1175 1075);
FORCEPROP 1 LAST VOLTAGE 0.0V
J 0
(-1295 1082);
DISPLAY 0.340426 (-1295 1082);
PAINT SKYBLUE (-1295 1082);
DISPLAY INVISIBLE (-1295 1082);
FORCEPROP 2 LAST CDS_LIB mstr_symbols
J 0
(-1250 1125);
PAINT ORANGE (-1250 1125);
DISPLAY INVISIBLE (-1250 1125);
FORCEPROP 1 LAST BODY_TYPE PLUMBING
J 0
(-1295 1082);
DISPLAY 0.340426 (-1295 1082);
PAINT GREEN (-1295 1082);
DISPLAY INVISIBLE (-1295 1082);
FORCEPROP 1 LAST HDL_POWER GND
J 0
(-1250 1275);
DISPLAY 0.872340 (-1250 1275);
PAINT GREEN (-1250 1275);
DISPLAY INVISIBLE (-1250 1275);
FORCEADD OFFPAGE..1
(-3050 2100);
FORCEPROP 2 LAST $XR0 141 
J 0
(-3752 2100);
DISPLAY 0.638298 (-3752 2100);
PAINT MONO (-3752 2100);
FORCEPROP 2 LAST CDS_LIB mstr_standard
J 0
(-3050 2100);
PAINT ORANGE (-3050 2100);
DISPLAY INVISIBLE (-3050 2100);
FORCEPROP 2 LAST PATH I42
J 0
(-3000 2175);
DISPLAY 1.021277 (-3000 2175);
PAINT ORANGE (-3000 2175);
DISPLAY INVISIBLE (-3000 2175);
FORCEPROP 1 LAST OFFPAGE TRUE
J 0
(-2725 1975);
DISPLAY 0.872340 (-2725 1975);
PAINT GREEN (-2725 1975);
DISPLAY INVISIBLE (-2725 1975);
FORCEPROP 1 LAST COMMENT_BODY TRUE
J 0
(-2925 2000);
DISPLAY 0.872340 (-2925 2000);
PAINT GREEN (-2925 2000);
DISPLAY INVISIBLE (-2925 2000);
FORCEADD CAP_A..1
(-6075 575);
FORCEPROP 1 LAST MATERIAL X7R
J 0
(-6025 475);
DISPLAY 0.617021 (-6025 475);
PAINT SKYBLUE (-6025 475);
FORCEPROP 1 LAST TOLERANCE 10%
J 0
(-6025 525);
DISPLAY 0.617021 (-6025 525);
PAINT SKYBLUE (-6025 525);
FORCEPROP 1 LASTPIN (-6075 475) $PN 2
J 0
(-6065 455);
DISPLAY 0.617021 (-6065 455);
PAINT ORANGE (-6065 455);
FORCEPROP 1 LAST PACK_TYPE 0402V
J 0
(-6025 375);
DISPLAY 0.617021 (-6025 375);
PAINT SKYBLUE (-6025 375);
FORCEPROP 1 LAST PART_NUMBER A36096-030
J 0
(-6025 425);
DISPLAY 0.617021 (-6025 425);
PAINT BLUE (-6025 425);
FORCEPROP 1 LASTPIN (-6075 675) $PN 1
J 0
(-6065 655);
DISPLAY 0.617021 (-6065 655);
PAINT ORANGE (-6065 655);
FORCEPROP 1 LAST VOLTAGE 16V
J 0
(-6025 575);
DISPLAY 0.617021 (-6025 575);
PAINT SKYBLUE (-6025 575);
FORCEPROP 1 LAST LOCATION C9G4
J 0
(-6025 675);
DISPLAY 0.617021 (-6025 675);
PAINT AQUA (-6025 675);
FORCEPROP 1 LAST VALUE 0.1UF
J 0
(-6025 625);
DISPLAY 0.617021 (-6025 625);
PAINT SKYBLUE (-6025 625);
FORCEPROP 0 LAST GROUP NI_I210&RJ45
J 0
(-6025 300);
DISPLAY 0.638298 (-6025 300);
PAINT BROWN (-6025 300);
DISPLAY BOTH (-6025 300);
FORCEPROP 2 LAST CDS_LIB dev_discrete
J 0
(-6075 575);
PAINT ORANGE (-6075 575);
DISPLAY INVISIBLE (-6075 575);
FORCEPROP 1 LAST PATH I46
J 0
(-6025 725);
DISPLAY 0.978723 (-6025 725);
PAINT WHITE (-6025 725);
DISPLAY INVISIBLE (-6025 725);
FORCEPROP 2 LAST ROOM NIC_SPRV
J 0
(-6025 725);
DISPLAY 1.021277 (-6025 725);
PAINT ORANGE (-6025 725);
DISPLAY INVISIBLE (-6025 725);
FORCEPROP 2 LAST CDS_LOCATION C9G4
J 0
(-6025 675);
DISPLAY 0.617021 (-6025 675);
PAINT AQUA (-6025 675);
DISPLAY INVISIBLE (-6025 675);
FORCEPROP 2 LAST BOM_COST NT_GBE_BASE
J 0
(-6025 775);
DISPLAY 1.021277 (-6025 775);
PAINT ORANGE (-6025 775);
DISPLAY INVISIBLE (-6025 775);
FORCEPROP 2 LAST CDS_SEC 1
J 0
(-6025 725);
PAINT ORANGE (-6025 725);
DISPLAY INVISIBLE (-6025 725);
FORCEPROP 2 LAST SEC_TYPE 0402V
J 0
(-6025 775);
DISPLAY 1.021277 (-6025 775);
PAINT ORANGE (-6025 775);
DISPLAY INVISIBLE (-6025 775);
FORCEPROP 2 LAST SEC 1
J 0
(-6025 775);
PAINT MONO (-6025 775);
DISPLAY INVISIBLE (-6025 775);
FORCEADD CAP_A..1
(-6400 575);
FORCEPROP 1 LAST MATERIAL X7R
J 0
(-6350 475);
DISPLAY 0.617021 (-6350 475);
PAINT SKYBLUE (-6350 475);
FORCEPROP 1 LASTPIN (-6400 475) $PN 2
J 0
(-6390 455);
DISPLAY 0.617021 (-6390 455);
PAINT ORANGE (-6390 455);
FORCEPROP 1 LASTPIN (-6400 675) $PN 1
J 0
(-6390 655);
DISPLAY 0.617021 (-6390 655);
PAINT ORANGE (-6390 655);
FORCEPROP 1 LAST PACK_TYPE 0402V
J 0
(-6350 375);
DISPLAY 0.617021 (-6350 375);
PAINT SKYBLUE (-6350 375);
FORCEPROP 1 LAST PART_NUMBER A36096-030
J 0
(-6350 425);
DISPLAY 0.617021 (-6350 425);
PAINT BLUE (-6350 425);
FORCEPROP 1 LAST VALUE 0.1UF
J 0
(-6350 625);
DISPLAY 0.617021 (-6350 625);
PAINT SKYBLUE (-6350 625);
FORCEPROP 1 LAST LOCATION C9G6
J 0
(-6350 675);
DISPLAY 0.617021 (-6350 675);
PAINT AQUA (-6350 675);
FORCEPROP 1 LAST VOLTAGE 16V
J 0
(-6350 575);
DISPLAY 0.617021 (-6350 575);
PAINT SKYBLUE (-6350 575);
FORCEPROP 1 LAST TOLERANCE 10%
J 0
(-6350 525);
DISPLAY 0.617021 (-6350 525);
PAINT SKYBLUE (-6350 525);
FORCEPROP 0 LAST GROUP NI_I210&RJ45
J 0
(-6350 250);
DISPLAY 0.638298 (-6350 250);
PAINT BROWN (-6350 250);
DISPLAY BOTH (-6350 250);
FORCEPROP 2 LAST CDS_LIB dev_discrete
J 0
(-6400 575);
PAINT ORANGE (-6400 575);
DISPLAY INVISIBLE (-6400 575);
FORCEPROP 2 LAST CDS_LOCATION C9G6
J 0
(-6350 675);
DISPLAY 0.617021 (-6350 675);
PAINT AQUA (-6350 675);
DISPLAY INVISIBLE (-6350 675);
FORCEPROP 2 LAST CDS_SEC 1
J 0
(-6350 725);
PAINT ORANGE (-6350 725);
DISPLAY INVISIBLE (-6350 725);
FORCEPROP 2 LAST ROOM NIC_SPRV
J 0
(-6350 725);
DISPLAY 1.021277 (-6350 725);
PAINT ORANGE (-6350 725);
DISPLAY INVISIBLE (-6350 725);
FORCEPROP 1 LAST PATH I47
J 0
(-6350 725);
DISPLAY 0.978723 (-6350 725);
PAINT WHITE (-6350 725);
DISPLAY INVISIBLE (-6350 725);
FORCEPROP 2 LAST BOM_COST NT_GBE_BASE
J 0
(-6350 775);
DISPLAY 1.021277 (-6350 775);
PAINT ORANGE (-6350 775);
DISPLAY INVISIBLE (-6350 775);
FORCEPROP 2 LAST SEC_TYPE 0402V
J 0
(-6350 775);
DISPLAY 1.021277 (-6350 775);
PAINT ORANGE (-6350 775);
DISPLAY INVISIBLE (-6350 775);
FORCEPROP 2 LAST SEC 1
J 0
(-6350 775);
PAINT MONO (-6350 775);
DISPLAY INVISIBLE (-6350 775);
FORCEADD CAP..1
(-6750 575);
FORCEPROP 1 LAST VALUE 1.0UF
J 0
(-6700 625);
DISPLAY 0.617021 (-6700 625);
PAINT SKYBLUE (-6700 625);
FORCEPROP 1 LAST PART_NUMBER G71842-007
J 0
(-6700 425);
DISPLAY 0.617021 (-6700 425);
PAINT BLUE (-6700 425);
FORCEPROP 1 LASTPIN (-6750 475) $PN 2
J 0
(-6740 455);
DISPLAY 0.617021 (-6740 455);
PAINT ORANGE (-6740 455);
FORCEPROP 1 LAST PACK_TYPE 0402
J 0
(-6700 375);
DISPLAY 0.617021 (-6700 375);
PAINT SKYBLUE (-6700 375);
FORCEPROP 1 LAST VOLTAGE 16V
J 0
(-6700 575);
DISPLAY 0.617021 (-6700 575);
PAINT SKYBLUE (-6700 575);
FORCEPROP 1 LAST MATERIAL X7S
J 0
(-6700 475);
DISPLAY 0.617021 (-6700 475);
PAINT SKYBLUE (-6700 475);
FORCEPROP 1 LASTPIN (-6750 675) $PN 1
J 0
(-6740 655);
DISPLAY 0.617021 (-6740 655);
PAINT ORANGE (-6740 655);
FORCEPROP 1 LAST LOCATION C9G5
J 0
(-6700 675);
DISPLAY 0.617021 (-6700 675);
PAINT AQUA (-6700 675);
FORCEPROP 1 LAST TOLERANCE 10%
J 0
(-6700 525);
DISPLAY 0.617021 (-6700 525);
PAINT SKYBLUE (-6700 525);
FORCEPROP 0 LAST GROUP NI_I210&RJ45
J 0
(-6700 300);
DISPLAY 0.638298 (-6700 300);
PAINT BROWN (-6700 300);
DISPLAY BOTH (-6700 300);
FORCEPROP 2 LAST CDS_LIB mstr_discrete
J 0
(-6750 575);
PAINT ORANGE (-6750 575);
DISPLAY INVISIBLE (-6750 575);
FORCEPROP 2 LAST BOM_COST NT_GBE_BASE
J 0
(-6700 775);
DISPLAY 1.021277 (-6700 775);
PAINT ORANGE (-6700 775);
DISPLAY INVISIBLE (-6700 775);
FORCEPROP 2 LAST SEC_TYPE 0402
J 0
(-6700 775);
DISPLAY 1.021277 (-6700 775);
PAINT ORANGE (-6700 775);
DISPLAY INVISIBLE (-6700 775);
FORCEPROP 2 LAST SEC 1
J 0
(-6700 775);
PAINT MONO (-6700 775);
DISPLAY INVISIBLE (-6700 775);
FORCEPROP 2 LAST CDS_LOCATION C9G5
J 0
(-6700 675);
DISPLAY 0.617021 (-6700 675);
PAINT AQUA (-6700 675);
DISPLAY INVISIBLE (-6700 675);
FORCEPROP 1 LAST PATH I48
J 0
(-6700 725);
DISPLAY 0.978723 (-6700 725);
PAINT WHITE (-6700 725);
DISPLAY INVISIBLE (-6700 725);
FORCEPROP 2 LAST ROOM NIC_SPRV
J 0
(-6700 725);
DISPLAY 1.021277 (-6700 725);
PAINT ORANGE (-6700 725);
DISPLAY INVISIBLE (-6700 725);
FORCEADD OFFPAGE..2
(-5350 825);
FORCEPROP 2 LAST $XR0 141 
J 0
(-5161 825);
DISPLAY 0.638298 (-5161 825);
PAINT MONO (-5161 825);
FORCEPROP 2 LAST PATH I49
J 0
(-5300 900);
DISPLAY 1.021277 (-5300 900);
PAINT ORANGE (-5300 900);
DISPLAY INVISIBLE (-5300 900);
FORCEPROP 2 LAST CDS_LIB mstr_standard
J 0
(-5350 825);
PAINT ORANGE (-5350 825);
DISPLAY INVISIBLE (-5350 825);
FORCEPROP 1 LAST OFFPAGE TRUE
J 0
(-5025 700);
DISPLAY 0.872340 (-5025 700);
PAINT GREEN (-5025 700);
DISPLAY INVISIBLE (-5025 700);
FORCEPROP 1 LAST COMMENT_BODY TRUE
J 0
(-5395 730);
DISPLAY 0.872340 (-5395 730);
PAINT GREEN (-5395 730);
DISPLAY INVISIBLE (-5395 730);
FORCEADD GND..1
(-6750 275);
FORCEPROP 3 LASTPIN (-6750 325) SIG_NAME GND\g
J 0
(-6740 335);
DISPLAY 0.659574 (-6740 335);
PAINT MONO (-6740 335);
DISPLAY INVISIBLE (-6740 335);
FORCEPROP 1 LAST VOLTAGE 0.0V
J 0
(-6795 232);
DISPLAY 0.340426 (-6795 232);
PAINT SKYBLUE (-6795 232);
DISPLAY INVISIBLE (-6795 232);
FORCEPROP 2 LAST CDS_LIB mstr_symbols
J 0
(-6750 275);
PAINT ORANGE (-6750 275);
DISPLAY INVISIBLE (-6750 275);
FORCEPROP 1 LAST SIZE 1B
J 0
(-6675 225);
DISPLAY 0.872340 (-6675 225);
PAINT AQUA (-6675 225);
DISPLAY INVISIBLE (-6675 225);
FORCEPROP 1 LAST PATH I50
J 0
(-6675 275);
DISPLAY 0.872340 (-6675 275);
PAINT AQUA (-6675 275);
DISPLAY INVISIBLE (-6675 275);
FORCEPROP 1 LAST BODY_TYPE PLUMBING
J 0
(-6795 232);
DISPLAY 0.340426 (-6795 232);
PAINT GREEN (-6795 232);
DISPLAY INVISIBLE (-6795 232);
FORCEPROP 1 LAST HDL_POWER GND
J 0
(-6750 425);
DISPLAY 0.872340 (-6750 425);
PAINT GREEN (-6750 425);
DISPLAY INVISIBLE (-6750 425);
FORCEADD RES..1
(-3275 3775);
FORCEPROP 1 LAST MATERIAL CHIP
J 0
(-2625 3775);
DISPLAY 0.617021 (-2625 3775);
PAINT SKYBLUE (-2625 3775);
FORCEPROP 1 LASTPIN (-3175 3775) $PN 2
J 0
(-3213 3787);
DISPLAY 0.787234 (-3213 3787);
PAINT ORANGE (-3213 3787);
FORCEPROP 1 LAST WATTAGE 1/16W
J 0
(-2775 3775);
DISPLAY 0.617021 (-2775 3775);
PAINT SKYBLUE (-2775 3775);
FORCEPROP 1 LAST LOCATION R9G9
J 0
(-3475 3775);
DISPLAY 0.617021 (-3475 3775);
PAINT AQUA (-3475 3775);
FORCEPROP 1 LAST VALUE 0.0
J 2
(-2825 3775);
DISPLAY 0.617021 (-2825 3775);
PAINT SKYBLUE (-2825 3775);
FORCEPROP 1 LAST PACK_TYPE 0402
J 0
(-2475 3775);
DISPLAY 0.617021 (-2475 3775);
PAINT SKYBLUE (-2475 3775);
FORCEPROP 1 LAST PART_NUMBER G21497-005
J 0
(-3125 3775);
DISPLAY 0.617021 (-3125 3775);
PAINT BLUE (-3125 3775);
FORCEPROP 1 LAST TOLERANCE 5%
J 0
(-3600 3775);
DISPLAY 0.617021 (-3600 3775);
PAINT SKYBLUE (-3600 3775);
FORCEPROP 1 LASTPIN (-3375 3775) $PN 1
J 0
(-3363 3787);
DISPLAY 0.787234 (-3363 3787);
PAINT ORANGE (-3363 3787);
FORCEPROP 0 LAST GROUP NI_I210&RJ45
J 0
(-2350 3775);
DISPLAY 0.638298 (-2350 3775);
PAINT BROWN (-2350 3775);
DISPLAY BOTH (-2350 3775);
FORCEPROP 2 LAST BOM_COST NT_GBE_BASE
J 0
(-2925 3875);
DISPLAY 1.021277 (-2925 3875);
PAINT ORANGE (-2925 3875);
DISPLAY INVISIBLE (-2925 3875);
FORCEPROP 2 LAST ROOM NIC_SPRV
J 0
(-2925 3825);
DISPLAY 1.021277 (-2925 3825);
PAINT ORANGE (-2925 3825);
DISPLAY INVISIBLE (-2925 3825);
FORCEPROP 2 LAST CDS_LIB mstr_discrete
J 0
(-3275 3775);
PAINT MONO (-3275 3775);
DISPLAY INVISIBLE (-3275 3775);
FORCEPROP 1 LAST PATH I75
J 0
(-3325 3925);
DISPLAY 0.978723 (-3325 3925);
PAINT WHITE (-3325 3925);
DISPLAY INVISIBLE (-3325 3925);
FORCEPROP 2 LAST CDS_LOCATION R9G9
J 0
(-3375 3775);
DISPLAY 0.617021 (-3375 3775);
PAINT AQUA (-3375 3775);
DISPLAY INVISIBLE (-3375 3775);
FORCEPROP 2 LAST SEC 1
J 0
(-3325 3975);
PAINT MONO (-3325 3975);
DISPLAY INVISIBLE (-3325 3975);
FORCEPROP 2 LAST SEC_TYPE 0402
J 0
(-3325 3975);
DISPLAY 1.021277 (-3325 3975);
PAINT ORANGE (-3325 3975);
DISPLAY INVISIBLE (-3325 3975);
FORCEADD RES..1
(-3275 3725);
FORCEPROP 1 LASTPIN (-3175 3725) $PN 2
J 0
(-3213 3737);
DISPLAY 0.787234 (-3213 3737);
PAINT ORANGE (-3213 3737);
FORCEPROP 1 LAST MATERIAL CHIP
J 0
(-2625 3725);
DISPLAY 0.617021 (-2625 3725);
PAINT SKYBLUE (-2625 3725);
FORCEPROP 1 LAST WATTAGE 1/16W
J 0
(-2775 3725);
DISPLAY 0.617021 (-2775 3725);
PAINT SKYBLUE (-2775 3725);
FORCEPROP 1 LAST PACK_TYPE 0402
J 0
(-2475 3725);
DISPLAY 0.617021 (-2475 3725);
PAINT SKYBLUE (-2475 3725);
FORCEPROP 1 LAST VALUE 0.0
J 2
(-2825 3725);
DISPLAY 0.617021 (-2825 3725);
PAINT SKYBLUE (-2825 3725);
FORCEPROP 1 LAST PART_NUMBER G21497-005
J 0
(-3125 3725);
DISPLAY 0.617021 (-3125 3725);
PAINT BLUE (-3125 3725);
FORCEPROP 1 LAST LOCATION R9G11
J 0
(-3475 3725);
DISPLAY 0.617021 (-3475 3725);
PAINT AQUA (-3475 3725);
FORCEPROP 1 LASTPIN (-3375 3725) $PN 1
J 0
(-3363 3737);
DISPLAY 0.787234 (-3363 3737);
PAINT ORANGE (-3363 3737);
FORCEPROP 1 LAST TOLERANCE 5%
J 0
(-3600 3725);
DISPLAY 0.617021 (-3600 3725);
PAINT SKYBLUE (-3600 3725);
FORCEPROP 0 LAST GROUP NI_I210&RJ45
J 0
(-2350 3725);
DISPLAY 0.638298 (-2350 3725);
PAINT BROWN (-2350 3725);
DISPLAY BOTH (-2350 3725);
FORCEPROP 2 LAST BOM_COST NT_GBE_BASE
J 0
(-2925 3825);
DISPLAY 1.021277 (-2925 3825);
PAINT ORANGE (-2925 3825);
DISPLAY INVISIBLE (-2925 3825);
FORCEPROP 2 LAST ROOM NIC_SPRV
J 0
(-2925 3775);
DISPLAY 1.021277 (-2925 3775);
PAINT ORANGE (-2925 3775);
DISPLAY INVISIBLE (-2925 3775);
FORCEPROP 2 LAST CDS_LIB mstr_discrete
J 0
(-3275 3725);
PAINT MONO (-3275 3725);
DISPLAY INVISIBLE (-3275 3725);
FORCEPROP 1 LAST PATH I76
J 0
(-3325 3875);
DISPLAY 0.978723 (-3325 3875);
PAINT WHITE (-3325 3875);
DISPLAY INVISIBLE (-3325 3875);
FORCEPROP 2 LAST CDS_LOCATION R9G11
J 0
(-3375 3725);
DISPLAY 0.617021 (-3375 3725);
PAINT AQUA (-3375 3725);
DISPLAY INVISIBLE (-3375 3725);
FORCEPROP 2 LAST SEC 1
J 0
(-3325 3925);
PAINT MONO (-3325 3925);
DISPLAY INVISIBLE (-3325 3925);
FORCEPROP 2 LAST SEC_TYPE 0402
J 0
(-3325 3925);
DISPLAY 1.021277 (-3325 3925);
PAINT ORANGE (-3325 3925);
DISPLAY INVISIBLE (-3325 3925);
FORCEADD RES..1
(-3275 3675);
FORCEPROP 1 LAST MATERIAL CHIP
J 0
(-2625 3675);
DISPLAY 0.617021 (-2625 3675);
PAINT SKYBLUE (-2625 3675);
FORCEPROP 1 LASTPIN (-3175 3675) $PN 2
J 0
(-3213 3687);
DISPLAY 0.787234 (-3213 3687);
PAINT ORANGE (-3213 3687);
FORCEPROP 1 LAST PART_NUMBER G21497-005
J 0
(-3125 3675);
DISPLAY 0.617021 (-3125 3675);
PAINT BLUE (-3125 3675);
FORCEPROP 1 LAST VALUE 0.0
J 2
(-2825 3675);
DISPLAY 0.617021 (-2825 3675);
PAINT SKYBLUE (-2825 3675);
FORCEPROP 1 LAST WATTAGE 1/16W
J 0
(-2775 3675);
DISPLAY 0.617021 (-2775 3675);
PAINT SKYBLUE (-2775 3675);
FORCEPROP 1 LAST LOCATION R9G18
J 0
(-3475 3675);
DISPLAY 0.617021 (-3475 3675);
PAINT AQUA (-3475 3675);
FORCEPROP 1 LAST PACK_TYPE 0402
J 0
(-2475 3675);
DISPLAY 0.617021 (-2475 3675);
PAINT SKYBLUE (-2475 3675);
FORCEPROP 1 LAST TOLERANCE 5%
J 0
(-3600 3675);
DISPLAY 0.617021 (-3600 3675);
PAINT SKYBLUE (-3600 3675);
FORCEPROP 1 LASTPIN (-3375 3675) $PN 1
J 0
(-3363 3687);
DISPLAY 0.787234 (-3363 3687);
PAINT ORANGE (-3363 3687);
FORCEPROP 0 LAST GROUP NI_I210&RJ45
J 0
(-2350 3675);
DISPLAY 0.638298 (-2350 3675);
PAINT BROWN (-2350 3675);
DISPLAY BOTH (-2350 3675);
FORCEPROP 2 LAST ROOM NIC_SPRV
J 0
(-2925 3725);
DISPLAY 1.021277 (-2925 3725);
PAINT ORANGE (-2925 3725);
DISPLAY INVISIBLE (-2925 3725);
FORCEPROP 2 LAST BOM_COST NT_GBE_BASE
J 0
(-2925 3775);
DISPLAY 1.021277 (-2925 3775);
PAINT ORANGE (-2925 3775);
DISPLAY INVISIBLE (-2925 3775);
FORCEPROP 2 LAST CDS_LIB mstr_discrete
J 0
(-3275 3675);
PAINT MONO (-3275 3675);
DISPLAY INVISIBLE (-3275 3675);
FORCEPROP 1 LAST PATH I77
J 0
(-3325 3825);
DISPLAY 0.978723 (-3325 3825);
PAINT WHITE (-3325 3825);
DISPLAY INVISIBLE (-3325 3825);
FORCEPROP 2 LAST CDS_LOCATION R9G18
J 0
(-3375 3675);
DISPLAY 0.617021 (-3375 3675);
PAINT AQUA (-3375 3675);
DISPLAY INVISIBLE (-3375 3675);
FORCEPROP 2 LAST SEC 1
J 0
(-3325 3875);
PAINT MONO (-3325 3875);
DISPLAY INVISIBLE (-3325 3875);
FORCEPROP 2 LAST SEC_TYPE 0402
J 0
(-3325 3875);
DISPLAY 1.021277 (-3325 3875);
PAINT ORANGE (-3325 3875);
DISPLAY INVISIBLE (-3325 3875);
FORCEADD RES..1
(-3275 3625);
FORCEPROP 1 LAST PART_NUMBER G21497-005
J 0
(-3125 3625);
DISPLAY 0.617021 (-3125 3625);
PAINT BLUE (-3125 3625);
FORCEPROP 1 LAST MATERIAL CHIP
J 0
(-2625 3625);
DISPLAY 0.617021 (-2625 3625);
PAINT SKYBLUE (-2625 3625);
FORCEPROP 1 LAST WATTAGE 1/16W
J 0
(-2775 3625);
DISPLAY 0.617021 (-2775 3625);
PAINT SKYBLUE (-2775 3625);
FORCEPROP 1 LAST PACK_TYPE 0402
J 0
(-2475 3625);
DISPLAY 0.617021 (-2475 3625);
PAINT SKYBLUE (-2475 3625);
FORCEPROP 1 LASTPIN (-3175 3625) $PN 2
J 0
(-3213 3637);
DISPLAY 0.787234 (-3213 3637);
PAINT ORANGE (-3213 3637);
FORCEPROP 1 LASTPIN (-3375 3625) $PN 1
J 0
(-3363 3637);
DISPLAY 0.787234 (-3363 3637);
PAINT ORANGE (-3363 3637);
FORCEPROP 1 LAST VALUE 0.0
J 2
(-2825 3625);
DISPLAY 0.617021 (-2825 3625);
PAINT SKYBLUE (-2825 3625);
FORCEPROP 1 LAST LOCATION R9G17
J 0
(-3475 3625);
DISPLAY 0.617021 (-3475 3625);
PAINT AQUA (-3475 3625);
FORCEPROP 1 LAST TOLERANCE 5%
J 0
(-3600 3625);
DISPLAY 0.617021 (-3600 3625);
PAINT SKYBLUE (-3600 3625);
FORCEPROP 0 LAST GROUP NI_I210&RJ45
J 0
(-2350 3625);
DISPLAY 0.638298 (-2350 3625);
PAINT BROWN (-2350 3625);
DISPLAY BOTH (-2350 3625);
FORCEPROP 2 LAST ROOM NIC_SPRV
J 0
(-2925 3675);
DISPLAY 1.021277 (-2925 3675);
PAINT ORANGE (-2925 3675);
DISPLAY INVISIBLE (-2925 3675);
FORCEPROP 2 LAST BOM_COST NT_GBE_BASE
J 0
(-2925 3725);
DISPLAY 1.021277 (-2925 3725);
PAINT ORANGE (-2925 3725);
DISPLAY INVISIBLE (-2925 3725);
FORCEPROP 2 LAST CDS_LIB mstr_discrete
J 0
(-3275 3625);
PAINT MONO (-3275 3625);
DISPLAY INVISIBLE (-3275 3625);
FORCEPROP 1 LAST PATH I78
J 0
(-3325 3775);
DISPLAY 0.978723 (-3325 3775);
PAINT WHITE (-3325 3775);
DISPLAY INVISIBLE (-3325 3775);
FORCEPROP 2 LAST CDS_LOCATION R9G17
J 0
(-3375 3625);
DISPLAY 0.617021 (-3375 3625);
PAINT AQUA (-3375 3625);
DISPLAY INVISIBLE (-3375 3625);
FORCEPROP 2 LAST SEC 1
J 0
(-3325 3825);
PAINT MONO (-3325 3825);
DISPLAY INVISIBLE (-3325 3825);
FORCEPROP 2 LAST SEC_TYPE 0402
J 0
(-3325 3825);
DISPLAY 1.021277 (-3325 3825);
PAINT ORANGE (-3325 3825);
DISPLAY INVISIBLE (-3325 3825);
FORCEADD RES..1
(-3275 3575);
FORCEPROP 1 LASTPIN (-3175 3575) $PN 2
J 0
(-3213 3587);
DISPLAY 0.787234 (-3213 3587);
PAINT ORANGE (-3213 3587);
FORCEPROP 1 LAST MATERIAL CHIP
J 0
(-2625 3575);
DISPLAY 0.617021 (-2625 3575);
PAINT SKYBLUE (-2625 3575);
FORCEPROP 1 LAST PACK_TYPE 0402
J 0
(-2475 3575);
DISPLAY 0.617021 (-2475 3575);
PAINT SKYBLUE (-2475 3575);
FORCEPROP 1 LAST PART_NUMBER G21497-005
J 0
(-3125 3575);
DISPLAY 0.617021 (-3125 3575);
PAINT BLUE (-3125 3575);
FORCEPROP 1 LAST VALUE 0.0
J 2
(-2825 3575);
DISPLAY 0.617021 (-2825 3575);
PAINT SKYBLUE (-2825 3575);
FORCEPROP 1 LAST WATTAGE 1/16W
J 0
(-2775 3575);
DISPLAY 0.617021 (-2775 3575);
PAINT SKYBLUE (-2775 3575);
FORCEPROP 1 LAST LOCATION R9G19
J 0
(-3475 3575);
DISPLAY 0.617021 (-3475 3575);
PAINT AQUA (-3475 3575);
FORCEPROP 1 LASTPIN (-3375 3575) $PN 1
J 0
(-3363 3587);
DISPLAY 0.787234 (-3363 3587);
PAINT ORANGE (-3363 3587);
FORCEPROP 1 LAST TOLERANCE 5%
J 0
(-3600 3575);
DISPLAY 0.617021 (-3600 3575);
PAINT SKYBLUE (-3600 3575);
FORCEPROP 0 LAST GROUP NI_I210&RJ45
J 0
(-2350 3575);
DISPLAY 0.638298 (-2350 3575);
PAINT BROWN (-2350 3575);
DISPLAY BOTH (-2350 3575);
FORCEPROP 2 LAST ROOM NIC_SPRV
J 0
(-2925 3625);
DISPLAY 1.021277 (-2925 3625);
PAINT ORANGE (-2925 3625);
DISPLAY INVISIBLE (-2925 3625);
FORCEPROP 2 LAST BOM_COST NT_GBE_BASE
J 0
(-2925 3675);
DISPLAY 1.021277 (-2925 3675);
PAINT ORANGE (-2925 3675);
DISPLAY INVISIBLE (-2925 3675);
FORCEPROP 2 LAST CDS_LIB mstr_discrete
J 0
(-3275 3575);
PAINT MONO (-3275 3575);
DISPLAY INVISIBLE (-3275 3575);
FORCEPROP 1 LAST PATH I79
J 0
(-3325 3725);
DISPLAY 0.978723 (-3325 3725);
PAINT WHITE (-3325 3725);
DISPLAY INVISIBLE (-3325 3725);
FORCEPROP 2 LAST CDS_LOCATION R9G19
J 0
(-3375 3575);
DISPLAY 0.617021 (-3375 3575);
PAINT AQUA (-3375 3575);
DISPLAY INVISIBLE (-3375 3575);
FORCEPROP 2 LAST SEC 1
J 0
(-3325 3775);
PAINT MONO (-3325 3775);
DISPLAY INVISIBLE (-3325 3775);
FORCEPROP 2 LAST SEC_TYPE 0402
J 0
(-3325 3775);
DISPLAY 1.021277 (-3325 3775);
PAINT ORANGE (-3325 3775);
DISPLAY INVISIBLE (-3325 3775);
FORCEADD RES..1
(-3275 3525);
FORCEPROP 1 LAST PART_NUMBER G21497-005
J 0
(-3125 3525);
DISPLAY 0.617021 (-3125 3525);
PAINT BLUE (-3125 3525);
FORCEPROP 1 LAST PACK_TYPE 0402
J 0
(-2475 3525);
DISPLAY 0.617021 (-2475 3525);
PAINT SKYBLUE (-2475 3525);
FORCEPROP 1 LASTPIN (-3175 3525) $PN 2
J 0
(-3213 3537);
DISPLAY 0.787234 (-3213 3537);
PAINT ORANGE (-3213 3537);
FORCEPROP 1 LAST MATERIAL CHIP
J 0
(-2625 3525);
DISPLAY 0.617021 (-2625 3525);
PAINT SKYBLUE (-2625 3525);
FORCEPROP 1 LAST WATTAGE 1/16W
J 0
(-2775 3525);
DISPLAY 0.617021 (-2775 3525);
PAINT SKYBLUE (-2775 3525);
FORCEPROP 1 LAST VALUE 0.0
J 2
(-2825 3525);
DISPLAY 0.617021 (-2825 3525);
PAINT SKYBLUE (-2825 3525);
FORCEPROP 1 LAST LOCATION R9G20
J 0
(-3475 3525);
DISPLAY 0.617021 (-3475 3525);
PAINT AQUA (-3475 3525);
FORCEPROP 1 LAST TOLERANCE 5%
J 0
(-3600 3525);
DISPLAY 0.617021 (-3600 3525);
PAINT SKYBLUE (-3600 3525);
FORCEPROP 1 LASTPIN (-3375 3525) $PN 1
J 0
(-3363 3537);
DISPLAY 0.787234 (-3363 3537);
PAINT ORANGE (-3363 3537);
FORCEPROP 0 LAST GROUP NI_I210&RJ45
J 0
(-2350 3525);
DISPLAY 0.638298 (-2350 3525);
PAINT BROWN (-2350 3525);
DISPLAY BOTH (-2350 3525);
FORCEPROP 2 LAST BOM_COST NT_GBE_BASE
J 0
(-2925 3625);
DISPLAY 1.021277 (-2925 3625);
PAINT ORANGE (-2925 3625);
DISPLAY INVISIBLE (-2925 3625);
FORCEPROP 2 LAST ROOM NIC_SPRV
J 0
(-2925 3575);
DISPLAY 1.021277 (-2925 3575);
PAINT ORANGE (-2925 3575);
DISPLAY INVISIBLE (-2925 3575);
FORCEPROP 2 LAST CDS_LIB mstr_discrete
J 0
(-3275 3525);
PAINT MONO (-3275 3525);
DISPLAY INVISIBLE (-3275 3525);
FORCEPROP 1 LAST PATH I80
J 0
(-3325 3675);
DISPLAY 0.978723 (-3325 3675);
PAINT WHITE (-3325 3675);
DISPLAY INVISIBLE (-3325 3675);
FORCEPROP 2 LAST CDS_LOCATION R9G20
J 0
(-3375 3525);
DISPLAY 0.617021 (-3375 3525);
PAINT AQUA (-3375 3525);
DISPLAY INVISIBLE (-3375 3525);
FORCEPROP 2 LAST SEC 1
J 0
(-3325 3725);
PAINT MONO (-3325 3725);
DISPLAY INVISIBLE (-3325 3725);
FORCEPROP 2 LAST SEC_TYPE 0402
J 0
(-3325 3725);
DISPLAY 1.021277 (-3325 3725);
PAINT ORANGE (-3325 3725);
DISPLAY INVISIBLE (-3325 3725);
FORCEADD RES..1
(-3275 3475);
FORCEPROP 1 LAST PART_NUMBER G21497-005
J 0
(-3125 3475);
DISPLAY 0.617021 (-3125 3475);
PAINT BLUE (-3125 3475);
FORCEPROP 1 LAST MATERIAL CHIP
J 0
(-2625 3475);
DISPLAY 0.617021 (-2625 3475);
PAINT SKYBLUE (-2625 3475);
FORCEPROP 1 LAST VALUE 0.0
J 2
(-2825 3475);
DISPLAY 0.617021 (-2825 3475);
PAINT SKYBLUE (-2825 3475);
FORCEPROP 1 LAST PACK_TYPE 0402
J 0
(-2475 3475);
DISPLAY 0.617021 (-2475 3475);
PAINT SKYBLUE (-2475 3475);
FORCEPROP 1 LASTPIN (-3175 3475) $PN 2
J 0
(-3213 3487);
DISPLAY 0.787234 (-3213 3487);
PAINT ORANGE (-3213 3487);
FORCEPROP 1 LAST LOCATION R9G24
J 0
(-3475 3475);
DISPLAY 0.617021 (-3475 3475);
PAINT AQUA (-3475 3475);
FORCEPROP 1 LASTPIN (-3375 3475) $PN 1
J 0
(-3363 3487);
DISPLAY 0.787234 (-3363 3487);
PAINT ORANGE (-3363 3487);
FORCEPROP 1 LAST TOLERANCE 5%
J 0
(-3600 3475);
DISPLAY 0.617021 (-3600 3475);
PAINT SKYBLUE (-3600 3475);
FORCEPROP 0 LAST GROUP NI_I210&RJ45
J 0
(-2350 3475);
DISPLAY 0.638298 (-2350 3475);
PAINT BROWN (-2350 3475);
DISPLAY BOTH (-2350 3475);
FORCEPROP 1 LAST WATTAGE 1/16W
J 0
(-2775 3475);
DISPLAY 0.617021 (-2775 3475);
PAINT SKYBLUE (-2775 3475);
FORCEPROP 2 LAST BOM_COST NT_GBE_BASE
J 0
(-2925 3575);
DISPLAY 1.021277 (-2925 3575);
PAINT ORANGE (-2925 3575);
DISPLAY INVISIBLE (-2925 3575);
FORCEPROP 2 LAST ROOM NIC_SPRV
J 0
(-2925 3525);
DISPLAY 1.021277 (-2925 3525);
PAINT ORANGE (-2925 3525);
DISPLAY INVISIBLE (-2925 3525);
FORCEPROP 2 LAST CDS_LIB mstr_discrete
J 0
(-3275 3475);
PAINT MONO (-3275 3475);
DISPLAY INVISIBLE (-3275 3475);
FORCEPROP 1 LAST PATH I81
J 0
(-3325 3625);
DISPLAY 0.978723 (-3325 3625);
PAINT WHITE (-3325 3625);
DISPLAY INVISIBLE (-3325 3625);
FORCEPROP 2 LAST CDS_LOCATION R9G24
J 0
(-3375 3475);
DISPLAY 0.617021 (-3375 3475);
PAINT AQUA (-3375 3475);
DISPLAY INVISIBLE (-3375 3475);
FORCEPROP 2 LAST SEC 1
J 0
(-3325 3675);
PAINT MONO (-3325 3675);
DISPLAY INVISIBLE (-3325 3675);
FORCEPROP 2 LAST SEC_TYPE 0402
J 0
(-3325 3675);
DISPLAY 1.021277 (-3325 3675);
PAINT ORANGE (-3325 3675);
DISPLAY INVISIBLE (-3325 3675);
FORCEADD RES..1
(-3275 3425);
FORCEPROP 1 LAST WATTAGE 1/16W
J 0
(-2775 3425);
DISPLAY 0.617021 (-2775 3425);
PAINT SKYBLUE (-2775 3425);
FORCEPROP 1 LAST VALUE 0.0
J 2
(-2825 3425);
DISPLAY 0.617021 (-2825 3425);
PAINT SKYBLUE (-2825 3425);
FORCEPROP 1 LAST MATERIAL CHIP
J 0
(-2625 3425);
DISPLAY 0.617021 (-2625 3425);
PAINT SKYBLUE (-2625 3425);
FORCEPROP 1 LAST PACK_TYPE 0402
J 0
(-2475 3425);
DISPLAY 0.617021 (-2475 3425);
PAINT SKYBLUE (-2475 3425);
FORCEPROP 1 LAST LOCATION R9G22
J 0
(-3475 3425);
DISPLAY 0.617021 (-3475 3425);
PAINT AQUA (-3475 3425);
FORCEPROP 1 LASTPIN (-3175 3425) $PN 2
J 0
(-3213 3437);
DISPLAY 0.787234 (-3213 3437);
PAINT ORANGE (-3213 3437);
FORCEPROP 1 LAST PART_NUMBER G21497-005
J 0
(-3125 3425);
DISPLAY 0.617021 (-3125 3425);
PAINT BLUE (-3125 3425);
FORCEPROP 1 LAST TOLERANCE 5%
J 0
(-3600 3425);
DISPLAY 0.617021 (-3600 3425);
PAINT SKYBLUE (-3600 3425);
FORCEPROP 1 LASTPIN (-3375 3425) $PN 1
J 0
(-3363 3437);
DISPLAY 0.787234 (-3363 3437);
PAINT ORANGE (-3363 3437);
FORCEPROP 0 LAST GROUP NI_I210&RJ45
J 0
(-2350 3425);
DISPLAY 0.638298 (-2350 3425);
PAINT BROWN (-2350 3425);
DISPLAY BOTH (-2350 3425);
FORCEPROP 2 LAST CDS_LOCATION R9G22
J 0
(-3375 3425);
DISPLAY 0.617021 (-3375 3425);
PAINT AQUA (-3375 3425);
DISPLAY INVISIBLE (-3375 3425);
FORCEPROP 1 LAST PATH I82
J 0
(-3325 3575);
DISPLAY 0.978723 (-3325 3575);
PAINT WHITE (-3325 3575);
DISPLAY INVISIBLE (-3325 3575);
FORCEPROP 2 LAST CDS_LIB mstr_discrete
J 0
(-3275 3425);
PAINT MONO (-3275 3425);
DISPLAY INVISIBLE (-3275 3425);
FORCEPROP 2 LAST BOM_COST NT_GBE_BASE
J 0
(-2925 3525);
DISPLAY 1.021277 (-2925 3525);
PAINT ORANGE (-2925 3525);
DISPLAY INVISIBLE (-2925 3525);
FORCEPROP 2 LAST ROOM NIC_SPRV
J 0
(-2925 3475);
DISPLAY 1.021277 (-2925 3475);
PAINT ORANGE (-2925 3475);
DISPLAY INVISIBLE (-2925 3475);
FORCEPROP 2 LAST SEC 1
J 0
(-3325 3625);
PAINT MONO (-3325 3625);
DISPLAY INVISIBLE (-3325 3625);
FORCEPROP 2 LAST SEC_TYPE 0402
J 0
(-3325 3625);
DISPLAY 1.021277 (-3325 3625);
PAINT ORANGE (-3325 3625);
DISPLAY INVISIBLE (-3325 3625);
FORCEADD OFFPAGE..3
(-1125 3775);
FORCEPROP 2 LAST $XR0 141 
J 0
(-911 3775);
DISPLAY 0.638298 (-911 3775);
PAINT MONO (-911 3775);
FORCEPROP 2 LAST CDS_LIB mstr_standard
J 0
(-1125 3775);
PAINT MONO (-1125 3775);
DISPLAY INVISIBLE (-1125 3775);
FORCEPROP 2 LAST PATH I83
J 0
(-1075 3850);
DISPLAY 1.021277 (-1075 3850);
PAINT ORANGE (-1075 3850);
DISPLAY INVISIBLE (-1075 3850);
FORCEPROP 1 LAST OFFPAGE TRUE
J 0
(-800 3650);
DISPLAY 0.872340 (-800 3650);
PAINT GREEN (-800 3650);
DISPLAY INVISIBLE (-800 3650);
FORCEPROP 1 LAST COMMENT_BODY TRUE
J 0
(-1175 3675);
DISPLAY 0.872340 (-1175 3675);
PAINT GREEN (-1175 3675);
DISPLAY INVISIBLE (-1175 3675);
FORCEADD OFFPAGE..3
(-1125 3725);
FORCEPROP 2 LAST $XR0 141 
J 0
(-911 3725);
DISPLAY 0.638298 (-911 3725);
PAINT MONO (-911 3725);
FORCEPROP 2 LAST CDS_LIB mstr_standard
J 0
(-1125 3725);
PAINT MONO (-1125 3725);
DISPLAY INVISIBLE (-1125 3725);
FORCEPROP 2 LAST PATH I84
J 0
(-925 3800);
DISPLAY 1.021277 (-925 3800);
PAINT ORANGE (-925 3800);
DISPLAY INVISIBLE (-925 3800);
FORCEPROP 1 LAST OFFPAGE TRUE
J 0
(-800 3600);
DISPLAY 0.872340 (-800 3600);
PAINT GREEN (-800 3600);
DISPLAY INVISIBLE (-800 3600);
FORCEPROP 1 LAST COMMENT_BODY TRUE
J 0
(-1175 3625);
DISPLAY 0.872340 (-1175 3625);
PAINT GREEN (-1175 3625);
DISPLAY INVISIBLE (-1175 3625);
FORCEADD OFFPAGE..3
(-1125 3675);
FORCEPROP 2 LAST $XR0 141 
J 0
(-911 3675);
DISPLAY 0.638298 (-911 3675);
PAINT MONO (-911 3675);
FORCEPROP 2 LAST CDS_LIB mstr_standard
J 0
(-1125 3675);
PAINT MONO (-1125 3675);
DISPLAY INVISIBLE (-1125 3675);
FORCEPROP 2 LAST PATH I85
J 0
(-925 3750);
DISPLAY 1.021277 (-925 3750);
PAINT ORANGE (-925 3750);
DISPLAY INVISIBLE (-925 3750);
FORCEPROP 1 LAST OFFPAGE TRUE
J 0
(-800 3550);
DISPLAY 0.872340 (-800 3550);
PAINT GREEN (-800 3550);
DISPLAY INVISIBLE (-800 3550);
FORCEPROP 1 LAST COMMENT_BODY TRUE
J 0
(-1175 3575);
DISPLAY 0.872340 (-1175 3575);
PAINT GREEN (-1175 3575);
DISPLAY INVISIBLE (-1175 3575);
FORCEADD OFFPAGE..3
(-1125 3625);
FORCEPROP 2 LAST $XR0 141 
J 0
(-911 3625);
DISPLAY 0.638298 (-911 3625);
PAINT MONO (-911 3625);
FORCEPROP 2 LAST CDS_LIB mstr_standard
J 0
(-1125 3625);
PAINT MONO (-1125 3625);
DISPLAY INVISIBLE (-1125 3625);
FORCEPROP 2 LAST PATH I86
J 0
(-925 3700);
DISPLAY 1.021277 (-925 3700);
PAINT ORANGE (-925 3700);
DISPLAY INVISIBLE (-925 3700);
FORCEPROP 1 LAST OFFPAGE TRUE
J 0
(-800 3500);
DISPLAY 0.872340 (-800 3500);
PAINT GREEN (-800 3500);
DISPLAY INVISIBLE (-800 3500);
FORCEPROP 1 LAST COMMENT_BODY TRUE
J 0
(-1175 3525);
DISPLAY 0.872340 (-1175 3525);
PAINT GREEN (-1175 3525);
DISPLAY INVISIBLE (-1175 3525);
FORCEADD OFFPAGE..3
(-1125 3575);
FORCEPROP 2 LAST $XR0 141 
J 0
(-911 3575);
DISPLAY 0.638298 (-911 3575);
PAINT MONO (-911 3575);
FORCEPROP 2 LAST CDS_LIB mstr_standard
J 0
(-1125 3575);
PAINT MONO (-1125 3575);
DISPLAY INVISIBLE (-1125 3575);
FORCEPROP 2 LAST PATH I87
J 0
(-925 3650);
DISPLAY 1.021277 (-925 3650);
PAINT ORANGE (-925 3650);
DISPLAY INVISIBLE (-925 3650);
FORCEPROP 1 LAST OFFPAGE TRUE
J 0
(-800 3450);
DISPLAY 0.872340 (-800 3450);
PAINT GREEN (-800 3450);
DISPLAY INVISIBLE (-800 3450);
FORCEPROP 1 LAST COMMENT_BODY TRUE
J 0
(-1175 3475);
DISPLAY 0.872340 (-1175 3475);
PAINT GREEN (-1175 3475);
DISPLAY INVISIBLE (-1175 3475);
FORCEADD OFFPAGE..3
(-1125 3525);
FORCEPROP 2 LAST $XR0 141 
J 0
(-911 3525);
DISPLAY 0.638298 (-911 3525);
PAINT MONO (-911 3525);
FORCEPROP 2 LAST CDS_LIB mstr_standard
J 0
(-1125 3525);
PAINT MONO (-1125 3525);
DISPLAY INVISIBLE (-1125 3525);
FORCEPROP 2 LAST PATH I88
J 0
(-925 3600);
DISPLAY 1.021277 (-925 3600);
PAINT ORANGE (-925 3600);
DISPLAY INVISIBLE (-925 3600);
FORCEPROP 1 LAST OFFPAGE TRUE
J 0
(-800 3400);
DISPLAY 0.872340 (-800 3400);
PAINT GREEN (-800 3400);
DISPLAY INVISIBLE (-800 3400);
FORCEPROP 1 LAST COMMENT_BODY TRUE
J 0
(-1175 3425);
DISPLAY 0.872340 (-1175 3425);
PAINT GREEN (-1175 3425);
DISPLAY INVISIBLE (-1175 3425);
FORCEADD OFFPAGE..3
(-1125 3475);
FORCEPROP 2 LAST $XR0 141 
J 0
(-911 3475);
DISPLAY 0.638298 (-911 3475);
PAINT MONO (-911 3475);
FORCEPROP 2 LAST CDS_LIB mstr_standard
J 0
(-1125 3475);
PAINT MONO (-1125 3475);
DISPLAY INVISIBLE (-1125 3475);
FORCEPROP 2 LAST PATH I89
J 0
(-925 3550);
DISPLAY 1.021277 (-925 3550);
PAINT ORANGE (-925 3550);
DISPLAY INVISIBLE (-925 3550);
FORCEPROP 1 LAST OFFPAGE TRUE
J 0
(-800 3350);
DISPLAY 0.872340 (-800 3350);
PAINT GREEN (-800 3350);
DISPLAY INVISIBLE (-800 3350);
FORCEPROP 1 LAST COMMENT_BODY TRUE
J 0
(-1175 3375);
DISPLAY 0.872340 (-1175 3375);
PAINT GREEN (-1175 3375);
DISPLAY INVISIBLE (-1175 3375);
FORCEADD OFFPAGE..3
(-1125 3425);
FORCEPROP 2 LAST $XR0 141 
J 0
(-911 3425);
DISPLAY 0.638298 (-911 3425);
PAINT MONO (-911 3425);
FORCEPROP 2 LAST CDS_LIB mstr_standard
J 0
(-1125 3425);
PAINT MONO (-1125 3425);
DISPLAY INVISIBLE (-1125 3425);
FORCEPROP 2 LAST PATH I90
J 0
(-925 3500);
DISPLAY 1.021277 (-925 3500);
PAINT ORANGE (-925 3500);
DISPLAY INVISIBLE (-925 3500);
FORCEPROP 1 LAST OFFPAGE TRUE
J 0
(-800 3300);
DISPLAY 0.872340 (-800 3300);
PAINT GREEN (-800 3300);
DISPLAY INVISIBLE (-800 3300);
FORCEPROP 1 LAST COMMENT_BODY TRUE
J 0
(-1175 3325);
DISPLAY 0.872340 (-1175 3325);
PAINT GREEN (-1175 3325);
DISPLAY INVISIBLE (-1175 3325);
FORCEADD OFFPAGE..6
(-4375 3425);
FORCEPROP 2 LAST $XR0 139 
J 0
(-4685 3425);
DISPLAY 0.638298 (-4685 3425);
PAINT MONO (-4685 3425);
FORCEPROP 2 LAST PATH I91
J 0
(-4325 3500);
DISPLAY 1.021277 (-4325 3500);
PAINT ORANGE (-4325 3500);
DISPLAY INVISIBLE (-4325 3500);
FORCEPROP 2 LAST CDS_LIB mstr_standard
J 0
(-4375 3425);
PAINT MONO (-4375 3425);
DISPLAY INVISIBLE (-4375 3425);
FORCEPROP 1 LAST OFFPAGE TRUE
J 0
(-4050 3300);
DISPLAY 0.872340 (-4050 3300);
PAINT GREEN (-4050 3300);
DISPLAY INVISIBLE (-4050 3300);
FORCEPROP 1 LAST COMMENT_BODY TRUE
J 0
(-4275 3350);
DISPLAY 0.872340 (-4275 3350);
PAINT GREEN (-4275 3350);
DISPLAY INVISIBLE (-4275 3350);
FORCEADD OFFPAGE..6
(-4375 3475);
FORCEPROP 2 LAST $XR0 139 
J 0
(-4685 3475);
DISPLAY 0.638298 (-4685 3475);
PAINT MONO (-4685 3475);
FORCEPROP 2 LAST PATH I92
J 0
(-4325 3550);
DISPLAY 1.021277 (-4325 3550);
PAINT ORANGE (-4325 3550);
DISPLAY INVISIBLE (-4325 3550);
FORCEPROP 2 LAST CDS_LIB mstr_standard
J 0
(-4375 3475);
PAINT MONO (-4375 3475);
DISPLAY INVISIBLE (-4375 3475);
FORCEPROP 1 LAST OFFPAGE TRUE
J 0
(-4050 3350);
DISPLAY 0.872340 (-4050 3350);
PAINT GREEN (-4050 3350);
DISPLAY INVISIBLE (-4050 3350);
FORCEPROP 1 LAST COMMENT_BODY TRUE
J 0
(-4275 3400);
DISPLAY 0.872340 (-4275 3400);
PAINT GREEN (-4275 3400);
DISPLAY INVISIBLE (-4275 3400);
FORCEADD OFFPAGE..6
(-4375 3525);
FORCEPROP 2 LAST $XR0 139 
J 0
(-4685 3525);
DISPLAY 0.638298 (-4685 3525);
PAINT MONO (-4685 3525);
FORCEPROP 2 LAST PATH I93
J 0
(-4325 3600);
DISPLAY 1.021277 (-4325 3600);
PAINT ORANGE (-4325 3600);
DISPLAY INVISIBLE (-4325 3600);
FORCEPROP 2 LAST CDS_LIB mstr_standard
J 0
(-4375 3525);
PAINT MONO (-4375 3525);
DISPLAY INVISIBLE (-4375 3525);
FORCEPROP 1 LAST OFFPAGE TRUE
J 0
(-4050 3400);
DISPLAY 0.872340 (-4050 3400);
PAINT GREEN (-4050 3400);
DISPLAY INVISIBLE (-4050 3400);
FORCEPROP 1 LAST COMMENT_BODY TRUE
J 0
(-4275 3450);
DISPLAY 0.872340 (-4275 3450);
PAINT GREEN (-4275 3450);
DISPLAY INVISIBLE (-4275 3450);
FORCEADD OFFPAGE..6
(-4375 3575);
FORCEPROP 2 LAST $XR0 139 
J 0
(-4685 3575);
DISPLAY 0.638298 (-4685 3575);
PAINT MONO (-4685 3575);
FORCEPROP 2 LAST PATH I94
J 0
(-4325 3650);
DISPLAY 1.021277 (-4325 3650);
PAINT ORANGE (-4325 3650);
DISPLAY INVISIBLE (-4325 3650);
FORCEPROP 2 LAST CDS_LIB mstr_standard
J 0
(-4375 3575);
PAINT MONO (-4375 3575);
DISPLAY INVISIBLE (-4375 3575);
FORCEPROP 1 LAST OFFPAGE TRUE
J 0
(-4050 3450);
DISPLAY 0.872340 (-4050 3450);
PAINT GREEN (-4050 3450);
DISPLAY INVISIBLE (-4050 3450);
FORCEPROP 1 LAST COMMENT_BODY TRUE
J 0
(-4275 3500);
DISPLAY 0.872340 (-4275 3500);
PAINT GREEN (-4275 3500);
DISPLAY INVISIBLE (-4275 3500);
FORCEADD OFFPAGE..6
(-4775 4025);
FORCEPROP 2 LAST $XR0 139 
J 0
(-5085 4025);
DISPLAY 0.638298 (-5085 4025);
PAINT MONO (-5085 4025);
FORCEPROP 2 LAST PATH I95
J 0
(-4725 4100);
DISPLAY 1.021277 (-4725 4100);
PAINT ORANGE (-4725 4100);
DISPLAY INVISIBLE (-4725 4100);
FORCEPROP 2 LAST CDS_LIB mstr_standard
J 0
(-4775 4025);
PAINT MONO (-4775 4025);
DISPLAY INVISIBLE (-4775 4025);
FORCEPROP 1 LAST OFFPAGE TRUE
J 0
(-4450 3900);
DISPLAY 0.872340 (-4450 3900);
PAINT GREEN (-4450 3900);
DISPLAY INVISIBLE (-4450 3900);
FORCEPROP 1 LAST COMMENT_BODY TRUE
J 0
(-4675 3950);
DISPLAY 0.872340 (-4675 3950);
PAINT GREEN (-4675 3950);
DISPLAY INVISIBLE (-4675 3950);
FORCEADD OFFPAGE..6
(-4775 4075);
FORCEPROP 2 LAST $XR0 139 
J 0
(-5085 4075);
DISPLAY 0.638298 (-5085 4075);
PAINT MONO (-5085 4075);
FORCEPROP 2 LAST PATH I96
J 0
(-4725 4150);
DISPLAY 1.021277 (-4725 4150);
PAINT ORANGE (-4725 4150);
DISPLAY INVISIBLE (-4725 4150);
FORCEPROP 2 LAST CDS_LIB mstr_standard
J 0
(-4775 4075);
PAINT MONO (-4775 4075);
DISPLAY INVISIBLE (-4775 4075);
FORCEPROP 1 LAST OFFPAGE TRUE
J 0
(-4450 3950);
DISPLAY 0.872340 (-4450 3950);
PAINT GREEN (-4450 3950);
DISPLAY INVISIBLE (-4450 3950);
FORCEPROP 1 LAST COMMENT_BODY TRUE
J 0
(-4675 4000);
DISPLAY 0.872340 (-4675 4000);
PAINT GREEN (-4675 4000);
DISPLAY INVISIBLE (-4675 4000);
FORCEADD OFFPAGE..6
(-4775 4125);
FORCEPROP 2 LAST $XR0 139 
J 0
(-5085 4125);
DISPLAY 0.638298 (-5085 4125);
PAINT MONO (-5085 4125);
FORCEPROP 2 LAST PATH I97
J 0
(-4725 4200);
DISPLAY 1.021277 (-4725 4200);
PAINT ORANGE (-4725 4200);
DISPLAY INVISIBLE (-4725 4200);
FORCEPROP 2 LAST CDS_LIB mstr_standard
J 0
(-4775 4125);
PAINT MONO (-4775 4125);
DISPLAY INVISIBLE (-4775 4125);
FORCEPROP 1 LAST OFFPAGE TRUE
J 0
(-4450 4000);
DISPLAY 0.872340 (-4450 4000);
PAINT GREEN (-4450 4000);
DISPLAY INVISIBLE (-4450 4000);
FORCEPROP 1 LAST COMMENT_BODY TRUE
J 0
(-4675 4050);
DISPLAY 0.872340 (-4675 4050);
PAINT GREEN (-4675 4050);
DISPLAY INVISIBLE (-4675 4050);
FORCEADD OFFPAGE..6
(-4775 4175);
FORCEPROP 2 LAST $XR0 139 
J 0
(-5085 4175);
DISPLAY 0.638298 (-5085 4175);
PAINT MONO (-5085 4175);
FORCEPROP 2 LAST PATH I98
J 0
(-4725 4250);
DISPLAY 1.021277 (-4725 4250);
PAINT ORANGE (-4725 4250);
DISPLAY INVISIBLE (-4725 4250);
FORCEPROP 2 LAST CDS_LIB mstr_standard
J 0
(-4775 4175);
PAINT MONO (-4775 4175);
DISPLAY INVISIBLE (-4775 4175);
FORCEPROP 1 LAST OFFPAGE TRUE
J 0
(-4450 4050);
DISPLAY 0.872340 (-4450 4050);
PAINT GREEN (-4450 4050);
DISPLAY INVISIBLE (-4450 4050);
FORCEPROP 1 LAST COMMENT_BODY TRUE
J 0
(-4675 4100);
DISPLAY 0.872340 (-4675 4100);
PAINT GREEN (-4675 4100);
DISPLAY INVISIBLE (-4675 4100);
FORCEADD CAP..2
(-2875 4425);
FORCEPROP 1 LAST VALUE 4700PF
J 2
(-2950 4425);
DISPLAY 0.617021 (-2950 4425);
PAINT SKYBLUE (-2950 4425);
FORCEPROP 1 LASTPIN (-2975 4425) $PN 1
J 0
(-2985 4440);
DISPLAY 0.787234 (-2985 4440);
PAINT ORANGE (-2985 4440);
FORCEPROP 1 LAST PACK_TYPE 0402LF
J 0
(-2250 4425);
DISPLAY 0.617021 (-2250 4425);
PAINT SKYBLUE (-2250 4425);
FORCEPROP 1 LAST TOLERANCE 10%
J 2
(-2475 4425);
DISPLAY 0.617021 (-2475 4425);
PAINT SKYBLUE (-2475 4425);
FORCEPROP 1 LAST VOLTAGE 50V
J 0
(-2400 4425);
DISPLAY 0.617021 (-2400 4425);
PAINT SKYBLUE (-2400 4425);
FORCEPROP 1 LAST LOCATION C9G9
J 1
(-3525 4425);
DISPLAY 0.617021 (-3525 4425);
PAINT AQUA (-3525 4425);
FORCEPROP 1 LAST PART_NUMBER A36096-066
J 1
(-3300 4425);
DISPLAY 0.617021 (-3300 4425);
PAINT BLUE (-3300 4425);
FORCEPROP 1 LAST MATERIAL EMPTY
J 0
(-2750 4425);
DISPLAY 0.617021 (-2750 4425);
PAINT RED (-2750 4425);
FORCEPROP 1 LASTPIN (-2775 4425) $PN 2
J 0
(-2790 4440);
DISPLAY 0.787234 (-2790 4440);
PAINT ORANGE (-2790 4440);
FORCEPROP 0 LAST GROUP NI_I210&RJ45
J 0
(-2800 4300);
DISPLAY 0.638298 (-2800 4300);
PAINT BROWN (-2800 4300);
DISPLAY BOTH (-2800 4300);
FORCEPROP 1 LAST PATH I99
J 0
(-2875 4625);
DISPLAY 0.978723 (-2875 4625);
PAINT WHITE (-2875 4625);
DISPLAY INVISIBLE (-2875 4625);
FORCEPROP 2 LAST NO_XNET_CONNECTION 1
J 0
(-2875 4675);
PAINT MONO (-2875 4675);
DISPLAY INVISIBLE (-2875 4675);
FORCEPROP 2 LAST ROOM NIC_SPRV
J 0
(-2625 4475);
DISPLAY 1.021277 (-2625 4475);
PAINT ORANGE (-2625 4475);
DISPLAY INVISIBLE (-2625 4475);
FORCEPROP 2 LAST BOM_COST NT_GBE_BASE
J 0
(-2625 4525);
DISPLAY 1.021277 (-2625 4525);
PAINT ORANGE (-2625 4525);
DISPLAY INVISIBLE (-2625 4525);
FORCEPROP 2 LAST CDS_LIB mstr_discrete
J 0
(-2875 4425);
PAINT MONO (-2875 4425);
DISPLAY INVISIBLE (-2875 4425);
FORCEPROP 2 LAST CDS_LOCATION C9G9
J 1
(-3325 4425);
DISPLAY 0.617021 (-3325 4425);
PAINT AQUA (-3325 4425);
DISPLAY INVISIBLE (-3325 4425);
FORCEPROP 2 LAST SEC 1
J 0
(-2875 4675);
PAINT MONO (-2875 4675);
DISPLAY INVISIBLE (-2875 4675);
FORCEPROP 2 LAST SEC_TYPE 0402LF
J 0
(-2875 4675);
DISPLAY 1.021277 (-2875 4675);
PAINT ORANGE (-2875 4675);
DISPLAY INVISIBLE (-2875 4675);
FORCEADD DNS..2
(-2870 4420);
PAINT RED (-2870 4420);
FORCEPROP 2 LAST CDS_LIB mstr_misc
J 0
(-2870 4420);
PAINT ORANGE (-2870 4420);
DISPLAY INVISIBLE (-2870 4420);
FORCEPROP 1 LAST COMMENT_BODY TRUE
R 1
J 0
(-2795 4195);
DISPLAY 0.872340 (-2795 4195);
PAINT GREEN (-2795 4195);
DISPLAY INVISIBLE (-2795 4195);
FORCEADD DNS..2
(-2820 4070);
PAINT RED (-2820 4070);
FORCEPROP 2 LAST CDS_LIB mstr_misc
J 0
(-2820 4070);
PAINT ORANGE (-2820 4070);
DISPLAY INVISIBLE (-2820 4070);
FORCEPROP 1 LAST COMMENT_BODY TRUE
R 1
J 0
(-2745 3845);
DISPLAY 0.872340 (-2745 3845);
PAINT GREEN (-2745 3845);
DISPLAY INVISIBLE (-2745 3845);
FORCEADD DNS..2
(-3095 4020);
PAINT RED (-3095 4020);
FORCEPROP 2 LAST CDS_LIB mstr_misc
J 0
(-3095 4020);
PAINT ORANGE (-3095 4020);
DISPLAY INVISIBLE (-3095 4020);
FORCEPROP 1 LAST COMMENT_BODY TRUE
R 1
J 0
(-3020 3795);
DISPLAY 0.872340 (-3020 3795);
PAINT GREEN (-3020 3795);
DISPLAY INVISIBLE (-3020 3795);
FORCEADD DNS..2
(-3145 4370);
PAINT RED (-3145 4370);
FORCEPROP 2 LAST CDS_LIB mstr_misc
J 0
(-3145 4370);
PAINT ORANGE (-3145 4370);
DISPLAY INVISIBLE (-3145 4370);
FORCEPROP 1 LAST COMMENT_BODY TRUE
R 1
J 0
(-3070 4145);
DISPLAY 0.872340 (-3070 4145);
PAINT GREEN (-3070 4145);
DISPLAY INVISIBLE (-3070 4145);
FORCEADD INTEL_CORP_BPAGE..1
(0 75);
FORCEPROP 1 LAST CDS_CON_LAST_MODIFIED Fri Jun 16 17:48:53 2017
J 0
(-1425 400);
DISPLAY 0.659574 (-1425 400);
PAINT GREEN (-1425 400);
DISPLAY INVISIBLE (-1425 400);
FORCEPROP 1 LAST CUSTOM_TXT_CDS <CURRENT_DESIGN_SHEET> OF <TOTAL_DESIGN_SHEETS>
J 0
(-500 100);
PAINT ORANGE (-500 100);
FORCEPROP 2 LAST CUSTOM_TXT_CDS <XR_PAGE_TITLE>
J 0
(-7890 5325);
DISPLAY 0.638298 (-7890 5325);
PAINT PINK (-7890 5325);
DISPLAY INVISIBLE (-7890 5325);
FORCEPROP 2 LAST CUSTOM_TXT_CDS <CON_LAST_MODIFIED>
J 0
(-4000 175);
DISPLAY 1.191489 (-4000 175);
PAINT ORANGE (-4000 175);
FORCEPROP 1 LAST SCH_TITLE LAN SPRINGVILLE I210 (3/3)
J 0
(-7950 125);
DISPLAY 1.212766 (-7950 125);
PAINT GREEN (-7950 125);
FORCEPROP 2 LAST CDS_LIB mstr_symbols
J 0
(0 75);
DISPLAY 0.489362 (0 75);
PAINT ORANGE (0 75);
DISPLAY INVISIBLE (0 75);
FORCEPROP 2 LAST PAGE_BORDER TRUE
J 0
(-7890 5325);
DISPLAY 0.425532 (-7890 5325);
PAINT PINK (-7890 5325);
DISPLAY INVISIBLE (-7890 5325);
FORCEPROP 1 LAST COMMENT_BODY TRUE
J 0
(12 87);
DISPLAY 0.319149 (12 87);
PAINT GREEN (12 87);
DISPLAY INVISIBLE (12 87);
FORCEPROP 2 LAST CDS_XR_PAGE_TITLE CR-141 : @BASEBOARD_FAB2_LIB.BASEBOARD_FAB2(SCH_1):PAGE141
J 0
(-7890 5325);
DISPLAY 0.638298 (-7890 5325);
PAINT PINK (-7890 5325);
DISPLAY INVISIBLE (-7890 5325);
WIRE 16 -1 (-3350 2225)(-3350 2275);
WIRE 16 -1 (-3650 2225)(-3650 2275);
WIRE 16 -1 (-3450 1750)(-3450 1800);
WIRE 16 -1 (-2050 1800)(-3450 1800);
WIRE 16 -1 (-3200 1250)(-3200 1200);
WIRE 16 -1 (-2975 1200)(-3200 1200);
WIRE 16 -1 (-3200 1200)(-3200 1150);
WIRE 16 -1 (-3200 900)(-3200 950);
WIRE 16 -1 (-3650 1200)(-3650 1150);
WIRE 16 -1 (-1250 2325)(-1250 2400);
WIRE 16 -1 (-1250 1175)(-1250 1250);
WIRE 16 -1 (-6750 325)(-6750 350);
WIRE 16 -1 (-6400 350)(-6750 350);
WIRE 16 -1 (-6750 350)(-6750 475);
WIRE 16 -1 (-6075 350)(-6400 350);
WIRE 16 -1 (-6400 475)(-6400 350);
WIRE 16 -1 (-6075 475)(-6075 350);
WIRE 16 -1 (-2050 1200)(-2775 1200);
FORCEPROP 2 LAST SIG_NAME NIC_LED_ACT_ANODE_R
J 0
(-2725 1210);
DISPLAY 0.617021 (-2725 1210);
PAINT ORANGE (-2725 1210);
FORCEPROP 2 LASTPROP $XRERR UNIQUE?
J 0
(-2965 1210);
DISPLAY 0.638298 (-2965 1210);
PAINT MONO (-2965 1210);
DISPLAY INVISIBLE (-2965 1210);
WIRE 16 -1 (-2050 1250)(-2050 1200);
WIRE 16 -1 (-2700 1450)(-2050 1450);
FORCEPROP 2 LAST SIG_NAME LED_LAN_1_R_N
J 0
(-2660 1460);
DISPLAY 0.617021 (-2660 1460);
PAINT ORANGE (-2660 1460);
FORCEPROP 2 LASTPROP $XRERR UNIQUE?
J 0
(-2900 1460);
DISPLAY 0.638298 (-2900 1460);
PAINT MONO (-2900 1460);
DISPLAY INVISIBLE (-2900 1460);
WIRE 16 -1 (-3000 1550)(-2050 1550);
FORCEPROP 2 LAST SIG_NAME GND_LAN_TRCT1234_C
J 0
(-2950 1560);
DISPLAY 0.617021 (-2950 1560);
PAINT ORANGE (-2950 1560);
WIRE 16 -1 (-3000 1600)(-2050 1600);
FORCEPROP 2 LAST SIG_NAME NIC_MDI_SPRV_RJ45_3_R_DN
J 0
(-2950 1610);
DISPLAY 0.617021 (-2950 1610);
PAINT ORANGE (-2950 1610);
WIRE 16 -1 (-3000 1650)(-2050 1650);
FORCEPROP 2 LAST SIG_NAME NIC_MDI_SPRV_RJ45_3_R_DP
J 0
(-2950 1660);
DISPLAY 0.617021 (-2950 1660);
PAINT ORANGE (-2950 1660);
WIRE 16 -1 (-3000 1700)(-2050 1700);
FORCEPROP 2 LAST SIG_NAME NIC_MDI_SPRV_RJ45_2_R_DN
J 0
(-2950 1710);
DISPLAY 0.617021 (-2950 1710);
PAINT ORANGE (-2950 1710);
WIRE 16 -1 (-3000 1750)(-2050 1750);
FORCEPROP 2 LAST SIG_NAME NIC_MDI_SPRV_RJ45_2_R_DP
J 0
(-2950 1760);
DISPLAY 0.617021 (-2950 1760);
PAINT ORANGE (-2950 1760);
WIRE 3 682 (-7700 3350)(-5700 3350);
WIRE 3 682 (-7700 4550)(-7700 3350);
WIRE 3 682 (-5700 3350)(-5700 4550);
WIRE 3 682 (-5700 4550)(-7700 4550);
WIRE 3 -1 (-1000 2900)(-4150 2900);
WIRE 3 -1 (-1000 750)(-1000 2900);
WIRE 3 -1 (-4150 2900)(-4150 750);
WIRE 3 -1 (-4150 750)(-1000 750);
WIRE 16 -1 (-2725 4075)(-1475 4075);
FORCEPROP 2 LAST SIG_NAME NIC_MDI_MNG_TX_DP
J 0
(-2150 4085);
DISPLAY 0.617021 (-2150 4085);
PAINT ORANGE (-2150 4085);
WIRE 16 -1 (-3000 4025)(-1475 4025);
FORCEPROP 2 LAST SIG_NAME NIC_MDI_MNG_TX_DN
J 0
(-2150 4035);
DISPLAY 0.617021 (-2150 4035);
PAINT ORANGE (-2150 4035);
WIRE 16 -1 (-3650 1400)(-3650 1450);
WIRE 16 -1 (-3700 1450)(-3650 1450);
WIRE 16 -1 (-2900 1450)(-3650 1450);
FORCEPROP 2 LAST SIG_NAME LED_LAN_1_N
J 0
(-3575 1460);
DISPLAY 0.617021 (-3575 1460);
PAINT ORANGE (-3575 1460);
WIRE 16 -1 (-3375 3675)(-3850 3675);
WIRE 16 -1 (-3850 3675)(-3850 4075);
WIRE 16 -1 (-3850 4075)(-2925 4075);
WIRE 16 -1 (-4725 4075)(-3850 4075);
FORCEPROP 2 LAST SIG_NAME NIC_SET_P_MDI_2_DP
J 0
(-4710 4085);
DISPLAY 0.617021 (-4710 4085);
PAINT ORANGE (-4710 4085);
WIRE 16 -1 (-4325 3525)(-3375 3525);
FORCEPROP 2 LAST SIG_NAME NIC_MDI_SPRV_RJ45_1_DN
J 0
(-4310 3535);
DISPLAY 0.617021 (-4310 3535);
PAINT ORANGE (-4310 3535);
WIRE 16 -1 (-4325 3575)(-3375 3575);
FORCEPROP 2 LAST SIG_NAME NIC_MDI_SPRV_RJ45_1_DP
J 0
(-4310 3585);
DISPLAY 0.617021 (-4310 3585);
PAINT ORANGE (-4310 3585);
WIRE 16 -1 (-4325 3425)(-3375 3425);
FORCEPROP 2 LAST SIG_NAME NIC_MDI_SPRV_RJ45_0_DN
J 0
(-4310 3435);
DISPLAY 0.617021 (-4310 3435);
PAINT ORANGE (-4310 3435);
WIRE 16 -1 (-4325 3475)(-3375 3475);
FORCEPROP 2 LAST SIG_NAME NIC_MDI_SPRV_RJ45_0_DP
J 0
(-4310 3485);
DISPLAY 0.617021 (-4310 3485);
PAINT ORANGE (-4310 3485);
WIRE 16 -1 (-3650 2725)(-3650 2475);
WIRE 16 -1 (-3650 2725)(-3700 2725);
WIRE 16 -1 (-2900 2725)(-3650 2725);
FORCEPROP 2 LAST SIG_NAME LED_LAN_2_N
J 0
(-3560 2735);
DISPLAY 0.617021 (-3560 2735);
PAINT ORANGE (-3560 2735);
WIRE 16 -1 (-3375 3775)(-3750 3775);
WIRE 16 -1 (-3750 4425)(-2975 4425);
WIRE 16 -1 (-4725 4175)(-3750 4175);
FORCEPROP 2 LAST SIG_NAME NIC_SER_P_MDI_3_DP
J 0
(-4710 4185);
DISPLAY 0.617021 (-4710 4185);
PAINT ORANGE (-4710 4185);
WIRE 16 -1 (-3750 3775)(-3750 4175);
WIRE 16 -1 (-3750 4175)(-3750 4425);
WIRE 16 -1 (-3700 2525)(-3350 2525);
FORCEPROP 2 LAST SIG_NAME LED_LAN_0_N
J 0
(-3535 2535);
DISPLAY 0.617021 (-3535 2535);
PAINT ORANGE (-3535 2535);
WIRE 16 -1 (-2900 2525)(-3350 2525);
WIRE 16 -1 (-3350 2475)(-3350 2525);
WIRE 16 -1 (-3375 3725)(-3800 3725);
WIRE 16 -1 (-3800 4375)(-3250 4375);
WIRE 16 -1 (-4725 4125)(-3800 4125);
FORCEPROP 2 LAST SIG_NAME NIC_SER_N_MDI_3_DN
J 0
(-4710 4135);
DISPLAY 0.617021 (-4710 4135);
PAINT ORANGE (-4710 4135);
WIRE 16 -1 (-3800 3725)(-3800 4125);
WIRE 16 -1 (-3800 4125)(-3800 4375);
WIRE 16 -1 (-3375 3625)(-3900 3625);
WIRE 16 -1 (-3900 4025)(-4725 4025);
FORCEPROP 2 LAST SIG_NAME NIC_SET_N_MDI_2_DN
J 0
(-4710 4035);
DISPLAY 0.617021 (-4710 4035);
PAINT ORANGE (-4710 4035);
WIRE 16 -1 (-3900 3625)(-3900 4025);
WIRE 16 -1 (-3900 4025)(-3200 4025);
WIRE 16 -1 (-3050 4375)(-1475 4375);
FORCEPROP 2 LAST SIG_NAME NIC_MDI_MNG_RX_DN
J 2
(-1500 4385);
DISPLAY 0.617021 (-1500 4385);
PAINT ORANGE (-1500 4385);
WIRE 16 -1 (-3175 3475)(-1175 3475);
FORCEPROP 2 LAST SIG_NAME NIC_MDI_SPRV_RJ45_0_R_DP
J 0
(-1785 3485);
DISPLAY 0.617021 (-1785 3485);
PAINT ORANGE (-1785 3485);
WIRE 16 -1 (-3175 3425)(-1175 3425);
FORCEPROP 2 LAST SIG_NAME NIC_MDI_SPRV_RJ45_0_R_DN
J 0
(-1785 3435);
DISPLAY 0.617021 (-1785 3435);
PAINT ORANGE (-1785 3435);
WIRE 16 -1 (-3175 3775)(-1175 3775);
FORCEPROP 2 LAST SIG_NAME NIC_MDI_SPRV_RJ45_3_R_DP
J 0
(-1785 3785);
DISPLAY 0.617021 (-1785 3785);
PAINT ORANGE (-1785 3785);
WIRE 3 682 (-1350 1050)(-1150 1050);
WIRE 3 682 (-1350 2525)(-1350 1050);
WIRE 3 682 (-1150 1050)(-1150 2525);
WIRE 3 682 (-1150 2525)(-1350 2525);
WIRE 16 -1 (-6750 675)(-6750 825);
WIRE 16 -1 (-6750 825)(-6400 825);
WIRE 16 -1 (-6400 675)(-6400 825);
WIRE 16 -1 (-6400 825)(-6075 825);
FORCEPROP 2 LAST SIG_NAME GND_LAN_TRCT1234_C
J 0
(-5935 835);
DISPLAY 0.617021 (-5935 835);
PAINT ORANGE (-5935 835);
WIRE 16 -1 (-6075 825)(-5400 825);
FORCEPROP 0 LAST VOLTAGE 0
J 0
(-5650 875);
DISPLAY 1.021277 (-5650 875);
PAINT ORANGE (-5650 875);
DISPLAY INVISIBLE (-5650 875);
WIRE 16 -1 (-6075 675)(-6075 825);
WIRE 16 -1 (-3000 1950)(-2050 1950);
FORCEPROP 2 LAST SIG_NAME NIC_MDI_SPRV_RJ45_0_R_DN
J 0
(-2950 1960);
DISPLAY 0.617021 (-2950 1960);
PAINT ORANGE (-2950 1960);
WIRE 16 -1 (-3000 2100)(-2050 2100);
FORCEPROP 2 LAST SIG_NAME GND_LAN_TRCT1234_C
J 0
(-2950 2110);
DISPLAY 0.617021 (-2950 2110);
PAINT ORANGE (-2950 2110);
WIRE 16 -1 (-3000 1900)(-2050 1900);
FORCEPROP 2 LAST SIG_NAME NIC_MDI_SPRV_RJ45_1_R_DP
J 0
(-2950 1910);
DISPLAY 0.617021 (-2950 1910);
PAINT ORANGE (-2950 1910);
WIRE 16 -1 (-3000 2000)(-2050 2000);
FORCEPROP 2 LAST SIG_NAME NIC_MDI_SPRV_RJ45_0_R_DP
J 0
(-2950 2010);
DISPLAY 0.617021 (-2950 2010);
PAINT ORANGE (-2950 2010);
WIRE 16 -1 (-2250 2200)(-2050 2200);
WIRE 16 -1 (-2700 2525)(-2250 2525);
FORCEPROP 2 LAST SIG_NAME LED_LAN_0_R_N
J 0
(-2625 2535);
DISPLAY 0.617021 (-2625 2535);
PAINT ORANGE (-2625 2535);
FORCEPROP 2 LASTPROP $XRERR UNIQUE?
J 0
(-2865 2535);
DISPLAY 0.638298 (-2865 2535);
PAINT MONO (-2865 2535);
DISPLAY INVISIBLE (-2865 2535);
WIRE 16 -1 (-2250 2525)(-2250 2200);
WIRE 16 -1 (-2200 2400)(-2050 2400);
WIRE 16 -1 (-2200 2725)(-2700 2725);
FORCEPROP 2 LAST SIG_NAME LED_LAN_2_R_N
J 0
(-2625 2735);
DISPLAY 0.617021 (-2625 2735);
PAINT ORANGE (-2625 2735);
FORCEPROP 2 LASTPROP $XRERR UNIQUE?
J 0
(-2865 2735);
DISPLAY 0.638298 (-2865 2735);
PAINT MONO (-2865 2735);
DISPLAY INVISIBLE (-2865 2735);
WIRE 16 -1 (-2200 2725)(-2200 2400);
WIRE 16 -1 (-3175 3525)(-1175 3525);
FORCEPROP 2 LAST SIG_NAME NIC_MDI_SPRV_RJ45_1_R_DN
J 0
(-1785 3535);
DISPLAY 0.617021 (-1785 3535);
PAINT ORANGE (-1785 3535);
WIRE 16 -1 (-3175 3575)(-1175 3575);
FORCEPROP 2 LAST SIG_NAME NIC_MDI_SPRV_RJ45_1_R_DP
J 0
(-1785 3585);
DISPLAY 0.617021 (-1785 3585);
PAINT ORANGE (-1785 3585);
WIRE 16 -1 (-3175 3675)(-1175 3675);
FORCEPROP 2 LAST SIG_NAME NIC_MDI_SPRV_RJ45_2_R_DP
J 0
(-1785 3685);
DISPLAY 0.617021 (-1785 3685);
PAINT ORANGE (-1785 3685);
WIRE 16 -1 (-3175 3725)(-1175 3725);
FORCEPROP 2 LAST SIG_NAME NIC_MDI_SPRV_RJ45_3_R_DN
J 0
(-1785 3735);
DISPLAY 0.617021 (-1785 3735);
PAINT ORANGE (-1785 3735);
WIRE 16 -1 (-3175 3625)(-1175 3625);
FORCEPROP 2 LAST SIG_NAME NIC_MDI_SPRV_RJ45_2_R_DN
J 0
(-1785 3635);
DISPLAY 0.617021 (-1785 3635);
PAINT ORANGE (-1785 3635);
WIRE 16 -1 (-2775 4425)(-1475 4425);
FORCEPROP 2 LAST SIG_NAME NIC_MDI_MNG_RX_DP
J 2
(-1500 4435);
DISPLAY 0.617021 (-1500 4435);
PAINT ORANGE (-1500 4435);
WIRE 16 3135 (-3350 3925)(-2650 3925);
WIRE 16 3135 (-3350 4600)(-3350 3925);
WIRE 16 3135 (-2650 3925)(-2650 4600);
WIRE 16 3135 (-2650 4600)(-3350 4600);
WIRE 16 3135 (-2800 3825)(-3675 3825);
WIRE 16 3135 (-2800 3225)(-2800 3825);
WIRE 16 3135 (-3675 3825)(-3675 3225);
WIRE 16 3135 (-3675 3225)(-2800 3225);
WIRE 16 -1 (-3000 1850)(-2050 1850);
FORCEPROP 2 LAST SIG_NAME NIC_MDI_SPRV_RJ45_1_R_DN
J 0
(-2950 1860);
DISPLAY 0.617021 (-2950 1860);
PAINT ORANGE (-2950 1860);
DOT 1 (-3200 1200);
DOT 1 (-3350 2525);
DOT 1 (-3650 2725);
DOT 1 (-3650 1450);
DOT 1 (-6400 350);
DOT 1 (-6750 350);
DOT 1 (-6400 825);
DOT 1 (-6075 825);
DOT 1 (-3850 4075);
DOT 1 (-3750 4175);
DOT 1 (-3800 4125);
DOT 1 (-3900 4025);
FORCENOTE
STUFF ON AS
(-3150 4525) 0;
DISPLAY LEFT (-3150 4525);
DISPLAY 0.808511 (-3150 4525);
PAINT PURPLE (-3150 4525);
FORCENOTE
TP DELETE RES 0307
(-7700 3275) 0;
DISPLAY LEFT (-7700 3275);
DISPLAY 1.021277 (-7700 3275);
PAINT RED (-7700 3275);
FORCENOTE
ROOM NT_FABRIC
(-7900 350) 0;
DISPLAY LEFT (-7900 350);
DISPLAY 1.212766 (-7900 350);
PAINT PURPLE (-7900 350);
FORCENOTE
STUFF ON AT
(-3650 3225) 0;
DISPLAY LEFT (-3650 3225);
DISPLAY 0.808511 (-3650 3225);
PAINT PURPLE (-3650 3225);
FORCENOTE
TP FAB1 CONNECT TO GND 0307
(-1900 975) 0;
DISPLAY LEFT (-1900 975);
DISPLAY 1.021277 (-1900 975);
PAINT RED (-1900 975);
QUIT
